G04 ================== begin FILE IDENTIFICATION RECORD ==================*
G04 Layout Name:  t6m_pdb_d_0928_1400_274.brd*
G04 Film Name:    gnd*
G04 File Format:  Gerber RS274X*
G04 File Origin:  Cadence Allegro 16.3-S048*
G04 Origin Date:  Tue Nov 26 11:01:50 2013*
G04 *
G04 Layer:  DRAWING FORMAT/TITLE_BLOCK*
G04 Layer:  VIA CLASS/GND*
G04 Layer:  PIN/GND*
G04 Layer:  MANUFACTURING/PHOTOPLOT_OUTLINE*
G04 Layer:  ETCH/GND*
G04 Layer:  DRAWING FORMAT/TITLE_DATA_GND*
G04 *
G04 Offset:    (0.00 0.00)*
G04 Mirror:    No*
G04 Mode:      Negative*
G04 Rotation:  0*
G04 FullContactRelief:  No*
G04 UndefLineWidth:     6.00*
G04 ================== end FILE IDENTIFICATION RECORD ====================*
%FSLAX25Y25*MOIN*%
%IR0*IPPOS*OFA0.00000B0.00000*MIA0B0*SFA1.00000B1.00000*%
%ADD26C,.03*%
%ADD34C,.04*%
%ADD38C,.05*%
%ADD17C,.06*%
%AMMACRO27*
4,1,36,0.0,.01,
-.001736,.009848,
-.00342,.009397,
-.005,.00866,
-.006428,.00766,
-.00766,.006428,
-.00866,.005,
-.009397,.00342,
-.009848,.001736,
-.01,0.0,
-.009848,-.001736,
-.009397,-.00342,
-.00866,-.005,
-.00766,-.006428,
-.006428,-.00766,
-.005,-.00866,
-.00342,-.009397,
-.001736,-.009848,
0.0,-.01,
.001736,-.009848,
.00342,-.009397,
.005,-.00866,
.006428,-.00766,
.00766,-.006428,
.00866,-.005,
.009397,-.00342,
.009848,-.001736,
.01,0.0,
.009848,.001736,
.009397,.00342,
.00866,.005,
.00766,.006428,
.006428,.00766,
.005,.00866,
.00342,.009397,
.001736,.009848,
0.0,.01,
0.0*
%
%ADD27MACRO27*%
%ADD29C,.064*%
%ADD13C,.056*%
%ADD18C,.048*%
%AMMACRO39*
4,1,36,0.0,.004,
.000695,.003939,
.001368,.003759,
.002,.003464,
.002571,.003064,
.003064,.002571,
.003464,.002,
.003759,.001368,
.003939,.000695,
.004,0.0,
.003939,-.000695,
.003759,-.001368,
.003464,-.002,
.003064,-.002571,
.002571,-.003064,
.002,-.003464,
.001368,-.003759,
.000695,-.003939,
0.0,-.004,
-.000695,-.003939,
-.001368,-.003759,
-.002,-.003464,
-.002571,-.003064,
-.003064,-.002571,
-.003464,-.002,
-.003759,-.001368,
-.003939,-.000695,
-.004,0.0,
-.003939,.000695,
-.003759,.001368,
-.003464,.002,
-.003064,.002571,
-.002571,.003064,
-.002,.003464,
-.001368,.003759,
-.000695,.003939,
0.0,.004,
180.*
%
%ADD39MACRO39*%
%AMMACRO33*
4,1,36,0.0,.009,
.001563,.008863,
.003078,.008457,
.0045,.007794,
.005785,.006894,
.006894,.005785,
.007794,.0045,
.008457,.003078,
.008863,.001563,
.009,0.0,
.008863,-.001563,
.008457,-.003078,
.007794,-.0045,
.006894,-.005785,
.005785,-.006894,
.0045,-.007794,
.003078,-.008457,
.001563,-.008863,
0.0,-.009,
-.001563,-.008863,
-.003078,-.008457,
-.0045,-.007794,
-.005785,-.006894,
-.006894,-.005785,
-.007794,-.0045,
-.008457,-.003078,
-.008863,-.001563,
-.009,0.0,
-.008863,.001563,
-.008457,.003078,
-.007794,.0045,
-.006894,.005785,
-.005785,.006894,
-.0045,.007794,
-.003078,.008457,
-.001563,.008863,
0.0,.009,
90.*
%
%ADD33MACRO33*%
%ADD22C,.077*%
%ADD10C,.059*%
%AMMACRO35*
4,1,36,0.0,.009,
.001563,.008863,
.003078,.008457,
.0045,.007794,
.005785,.006894,
.006894,.005785,
.007794,.0045,
.008457,.003078,
.008863,.001563,
.009,0.0,
.008863,-.001563,
.008457,-.003078,
.007794,-.0045,
.006894,-.005785,
.005785,-.006894,
.0045,-.007794,
.003078,-.008457,
.001563,-.008863,
0.0,-.009,
-.001563,-.008863,
-.003078,-.008457,
-.0045,-.007794,
-.005785,-.006894,
-.006894,-.005785,
-.007794,-.0045,
-.008457,-.003078,
-.008863,-.001563,
-.009,0.0,
-.008863,.001563,
-.008457,.003078,
-.007794,.0045,
-.006894,.005785,
-.005785,.006894,
-.0045,.007794,
-.003078,.008457,
-.001563,.008863,
0.0,.009,
0.0*
%
%ADD35MACRO35*%
%AMMACRO16*
4,1,15,.02438,.01377,
.026401,.009327,
.027619,.004601,
.027999,-.000265,
.027527,-.005123,
.02622,-.009825,
.02438,-.01377,
.02948,-.01887,
.032309,-.013464,
.034156,-.007649,
.034965,-.001602,
.034712,.004494,
.033405,.010454,
.031082,.016095,
.02948,.01887,
.02438,.01377,
90.*
4,1,15,.01377,-.02438,
.009327,-.026401,
.004601,-.027619,
-.000265,-.027999,
-.005123,-.027527,
-.009825,-.02622,
-.01377,-.02438,
-.01887,-.02948,
-.013464,-.032309,
-.007649,-.034156,
-.001602,-.034965,
.004494,-.034712,
.010454,-.033405,
.016095,-.031082,
.01887,-.02948,
.01377,-.02438,
90.*
4,1,15,-.02438,-.01377,
-.026401,-.009327,
-.027619,-.004601,
-.027999,.000265,
-.027527,.005123,
-.02622,.009825,
-.02438,.01377,
-.02948,.01887,
-.032309,.013464,
-.034156,.007649,
-.034965,.001602,
-.034712,-.004494,
-.033405,-.010454,
-.031082,-.016095,
-.02948,-.01887,
-.02438,-.01377,
90.*
4,1,15,-.01377,.02438,
-.009327,.026401,
-.004601,.027619,
.000265,.027999,
.005123,.027527,
.009825,.02622,
.01377,.02438,
.01887,.02948,
.013464,.032309,
.007649,.034156,
.001602,.034965,
-.004494,.034712,
-.010454,.033405,
-.016095,.031082,
-.01887,.02948,
-.01377,.02438,
90.*
%
%ADD16MACRO16*%
%AMMACRO25*
4,1,15,.02401,.0134,
.025972,.009027,
.027145,.00438,
.027493,-.0004,
.027006,-.005168,
.025698,-.009779,
.02401,-.0134,
.02912,-.01851,
.031892,-.013172,
.033695,-.007434,
.034474,-.00147,
.034205,.004538,
.032897,.010409,
.03059,.015964,
.02912,.01851,
.02401,.0134,
0.0*
4,1,15,.0134,-.02401,
.009027,-.025972,
.00438,-.027145,
-.0004,-.027493,
-.005168,-.027006,
-.009779,-.025698,
-.0134,-.02401,
-.01851,-.02912,
-.013172,-.031892,
-.007434,-.033695,
-.00147,-.034474,
.004538,-.034205,
.010409,-.032897,
.015964,-.03059,
.01851,-.02912,
.0134,-.02401,
0.0*
4,1,15,-.02401,-.0134,
-.025972,-.009027,
-.027145,-.00438,
-.027493,.0004,
-.027006,.005168,
-.025698,.009779,
-.02401,.0134,
-.02912,.01851,
-.031892,.013172,
-.033695,.007434,
-.034474,.00147,
-.034205,-.004538,
-.032897,-.010409,
-.03059,-.015964,
-.02912,-.01851,
-.02401,-.0134,
0.0*
4,1,15,-.0134,.02401,
-.009027,.025972,
-.00438,.027145,
.0004,.027493,
.005168,.027006,
.009779,.025698,
.0134,.02401,
.01851,.02912,
.013172,.031892,
.007434,.033695,
.00147,.034474,
-.004538,.034205,
-.010409,.032897,
-.015964,.03059,
-.01851,.02912,
-.0134,.02401,
0.0*
%
%ADD25MACRO25*%
%AMMACRO21*
4,1,17,.03273,.02212,
.036074,.0161,
.038322,.009592,
.039405,.002791,
.039291,-.004094,
.037983,-.010854,
.035521,-.017285,
.03273,-.02212,
.03775,-.02715,
.041891,-.020182,
.044759,-.012601,
.046267,-.004638,
.04637,.003467,
.045063,.011466,
.042388,.019117,
.038424,.026188,
.03775,.02715,
.03273,.02212,
0.0*
4,1,17,.02212,-.03273,
.0161,-.036074,
.009592,-.038322,
.002791,-.039405,
-.004094,-.039291,
-.010854,-.037983,
-.017285,-.035521,
-.02212,-.03273,
-.02715,-.03775,
-.020182,-.041891,
-.012601,-.044759,
-.004638,-.046267,
.003467,-.04637,
.011466,-.045063,
.019117,-.042388,
.026188,-.038424,
.02715,-.03775,
.02212,-.03273,
0.0*
4,1,17,-.03273,-.02212,
-.036074,-.0161,
-.038322,-.009592,
-.039405,-.002791,
-.039291,.004094,
-.037983,.010854,
-.035521,.017285,
-.03273,.02212,
-.03775,.02715,
-.041891,.020182,
-.044759,.012601,
-.046267,.004638,
-.04637,-.003467,
-.045063,-.011466,
-.042388,-.019117,
-.038424,-.026188,
-.03775,-.02715,
-.03273,-.02212,
0.0*
4,1,17,-.02212,.03273,
-.0161,.036074,
-.009592,.038322,
-.002791,.039405,
.004094,.039291,
.010854,.037983,
.017285,.035521,
.02212,.03273,
.02715,.03775,
.020182,.041891,
.012601,.044759,
.004638,.046267,
-.003467,.04637,
-.011466,.045063,
-.019117,.042388,
-.026188,.038424,
-.02715,.03775,
-.02212,.03273,
0.0*
%
%ADD21MACRO21*%
%ADD41O,.235X.274*%
%ADD19C,.125*%
%ADD12C,.162*%
%ADD40C,.235*%
%ADD42C,.345*%
%ADD31C,.129*%
%ADD14C,.156*%
%AMMACRO20*
4,1,36,0.0,.013,
-.002257,.012803,
-.004446,.012216,
-.0065,.011258,
-.008356,.009959,
-.009959,.008356,
-.011258,.0065,
-.012216,.004446,
-.012803,.002257,
-.013,0.0,
-.012803,-.002257,
-.012216,-.004446,
-.011258,-.0065,
-.009959,-.008356,
-.008356,-.009959,
-.0065,-.011258,
-.004446,-.012216,
-.002257,-.012803,
0.0,-.013,
.002257,-.012803,
.004446,-.012216,
.0065,-.011258,
.008356,-.009959,
.009959,-.008356,
.011258,-.0065,
.012216,-.004446,
.012803,-.002257,
.013,0.0,
.012803,.002257,
.012216,.004446,
.011258,.0065,
.009959,.008356,
.008356,.009959,
.0065,.011258,
.004446,.012216,
.002257,.012803,
0.0,.013,
270.*
%
%ADD20MACRO20*%
%AMMACRO32*
4,1,36,0.0,.009,
.001563,.008863,
.003078,.008457,
.0045,.007794,
.005785,.006894,
.006894,.005785,
.007794,.0045,
.008457,.003078,
.008863,.001563,
.009,0.0,
.008863,-.001563,
.008457,-.003078,
.007794,-.0045,
.006894,-.005785,
.005785,-.006894,
.0045,-.007794,
.003078,-.008457,
.001563,-.008863,
0.0,-.009,
-.001563,-.008863,
-.003078,-.008457,
-.0045,-.007794,
-.005785,-.006894,
-.006894,-.005785,
-.007794,-.0045,
-.008457,-.003078,
-.008863,-.001563,
-.009,0.0,
-.008863,.001563,
-.008457,.003078,
-.007794,.0045,
-.006894,.005785,
-.005785,.006894,
-.0045,.007794,
-.003078,.008457,
-.001563,.008863,
0.0,.009,
180.*
%
%ADD32MACRO32*%
%AMMACRO36*
4,1,36,0.0,.014,
.002431,.013787,
.004788,.013156,
.007,.012124,
.008999,.010725,
.010725,.008999,
.012124,.007,
.013156,.004788,
.013787,.002431,
.014,0.0,
.013787,-.002431,
.013156,-.004788,
.012124,-.007,
.010725,-.008999,
.008999,-.010725,
.007,-.012124,
.004788,-.013156,
.002431,-.013787,
0.0,-.014,
-.002431,-.013787,
-.004788,-.013156,
-.007,-.012124,
-.008999,-.010725,
-.010725,-.008999,
-.012124,-.007,
-.013156,-.004788,
-.013787,-.002431,
-.014,0.0,
-.013787,.002431,
-.013156,.004788,
-.012124,.007,
-.010725,.008999,
-.008999,.010725,
-.007,.012124,
-.004788,.013156,
-.002431,.013787,
0.0,.014,
180.*
%
%ADD36MACRO36*%
%ADD28C,.188*%
%AMMACRO11*
4,1,36,0.0,.004,
.000695,.003939,
.001368,.003759,
.002,.003464,
.002571,.003064,
.003064,.002571,
.003464,.002,
.003759,.001368,
.003939,.000695,
.004,0.0,
.003939,-.000695,
.003759,-.001368,
.003464,-.002,
.003064,-.002571,
.002571,-.003064,
.002,-.003464,
.001368,-.003759,
.000695,-.003939,
0.0,-.004,
-.000695,-.003939,
-.001368,-.003759,
-.002,-.003464,
-.002571,-.003064,
-.003064,-.002571,
-.003464,-.002,
-.003759,-.001368,
-.003939,-.000695,
-.004,0.0,
-.003939,.000695,
-.003759,.001368,
-.003464,.002,
-.003064,.002571,
-.002571,.003064,
-.002,.003464,
-.001368,.003759,
-.000695,.003939,
0.0,.004,
0.0*
%
%ADD11MACRO11*%
%AMMACRO30*
4,1,16,.02584,.01524,
.028094,.010521,
.029494,.005483,
.029998,.000278,
.029591,-.004935,
.028284,-.009999,
.026118,-.014758,
.02584,-.01524,
.03092,-.02032,
.033979,-.014642,
.036005,-.008519,
.036938,-.002138,
.036748,.004309,
.035441,.010625,
.033058,.016618,
.03092,.02032,
.02584,.01524,
270.*
4,1,16,.01524,-.02584,
.010521,-.028094,
.005483,-.029494,
.000278,-.029998,
-.004935,-.029591,
-.009999,-.028284,
-.014758,-.026118,
-.01524,-.02584,
-.02032,-.03092,
-.014642,-.033979,
-.008519,-.036005,
-.002138,-.036938,
.004309,-.036748,
.010625,-.035441,
.016618,-.033058,
.02032,-.03092,
.01524,-.02584,
270.*
4,1,16,-.02584,-.01524,
-.028094,-.010521,
-.029494,-.005483,
-.029998,-.000278,
-.029591,.004935,
-.028284,.009999,
-.026118,.014758,
-.02584,.01524,
-.03092,.02032,
-.033979,.014642,
-.036005,.008519,
-.036938,.002138,
-.036748,-.004309,
-.035441,-.010625,
-.033058,-.016618,
-.03092,-.02032,
-.02584,-.01524,
270.*
4,1,16,-.01524,.02584,
-.010521,.028094,
-.005483,.029494,
-.000278,.029998,
.004935,.029591,
.009999,.028284,
.014758,.026118,
.01524,.02584,
.02032,.03092,
.014642,.033979,
.008519,.036005,
.002138,.036938,
-.004309,.036748,
-.010625,.035441,
-.016618,.033058,
-.02032,.03092,
-.01524,.02584,
270.*
%
%ADD30MACRO30*%
%AMMACRO37*
4,1,15,.02291,.0123,
.024698,.008135,
.025735,.003723,
.025991,-.000803,
.025456,-.005304,
.024149,-.009644,
.02291,-.0123,
.02803,-.01742,
.030629,-.012288,
.032298,-.006783,
.032985,-.001071,
.03267,.004673,
.031362,.010275,
.029101,.015565,
.02803,.01742,
.02291,.0123,
180.*
4,1,15,.0123,-.02291,
.008135,-.024698,
.003723,-.025735,
-.000803,-.025991,
-.005304,-.025456,
-.009644,-.024149,
-.0123,-.02291,
-.01742,-.02803,
-.012288,-.030629,
-.006783,-.032298,
-.001071,-.032985,
.004673,-.03267,
.010275,-.031362,
.015565,-.029101,
.01742,-.02803,
.0123,-.02291,
180.*
4,1,15,-.02291,-.0123,
-.024698,-.008135,
-.025735,-.003723,
-.025991,.000803,
-.025456,.005304,
-.024149,.009644,
-.02291,.0123,
-.02803,.01742,
-.030629,.012288,
-.032298,.006783,
-.032985,.001071,
-.03267,-.004673,
-.031362,-.010275,
-.029101,-.015565,
-.02803,-.01742,
-.02291,-.0123,
180.*
4,1,15,-.0123,.02291,
-.008135,.024698,
-.003723,.025735,
.000803,.025991,
.005304,.025456,
.009644,.024149,
.0123,.02291,
.01742,.02803,
.012288,.030629,
.006783,.032298,
.001071,.032985,
-.004673,.03267,
-.010275,.031362,
-.015565,.029101,
-.01742,.02803,
-.0123,.02291,
180.*
%
%ADD37MACRO37*%
%AMMACRO24*
4,1,15,.02401,.0134,
.025972,.009027,
.027145,.00438,
.027493,-.0004,
.027006,-.005168,
.025698,-.009779,
.02401,-.0134,
.02912,-.01851,
.031892,-.013172,
.033695,-.007434,
.034474,-.00147,
.034205,.004538,
.032897,.010409,
.03059,.015964,
.02912,.01851,
.02401,.0134,
180.*
4,1,15,.0134,-.02401,
.009027,-.025972,
.00438,-.027145,
-.0004,-.027493,
-.005168,-.027006,
-.009779,-.025698,
-.0134,-.02401,
-.01851,-.02912,
-.013172,-.031892,
-.007434,-.033695,
-.00147,-.034474,
.004538,-.034205,
.010409,-.032897,
.015964,-.03059,
.01851,-.02912,
.0134,-.02401,
180.*
4,1,15,-.02401,-.0134,
-.025972,-.009027,
-.027145,-.00438,
-.027493,.0004,
-.027006,.005168,
-.025698,.009779,
-.02401,.0134,
-.02912,.01851,
-.031892,.013172,
-.033695,.007434,
-.034474,.00147,
-.034205,-.004538,
-.032897,-.010409,
-.03059,-.015964,
-.02912,-.01851,
-.02401,-.0134,
180.*
4,1,15,-.0134,.02401,
-.009027,.025972,
-.00438,.027145,
.0004,.027493,
.005168,.027006,
.009779,.025698,
.0134,.02401,
.01851,.02912,
.013172,.031892,
.007434,.033695,
.00147,.034474,
-.004538,.034205,
-.010409,.032897,
-.015964,.03059,
-.01851,.02912,
-.0134,.02401,
180.*
%
%ADD24MACRO24*%
%AMMACRO23*
4,1,17,.03056,.01996,
.033562,.01435,
.035544,.008304,
.036446,.002006,
.03624,-.004353,
.034934,-.01058,
.032566,-.016486,
.03056,-.01996,
.0356,-.025,
.0394,-.018438,
.042004,-.011316,
.043331,-.003851,
.043341,.003732,
.042034,.011201,
.039451,.018331,
.035668,.024903,
.0356,.025,
.03056,.01996,
270.*
4,1,17,.01996,-.03056,
.01435,-.033562,
.008304,-.035544,
.002006,-.036446,
-.004353,-.03624,
-.01058,-.034934,
-.016486,-.032566,
-.01996,-.03056,
-.025,-.0356,
-.018438,-.0394,
-.011316,-.042004,
-.003851,-.043331,
.003732,-.043341,
.011201,-.042034,
.018331,-.039451,
.024903,-.035668,
.025,-.0356,
.01996,-.03056,
270.*
4,1,17,-.03056,-.01996,
-.033562,-.01435,
-.035544,-.008304,
-.036446,-.002006,
-.03624,.004353,
-.034934,.01058,
-.032566,.016486,
-.03056,.01996,
-.0356,.025,
-.0394,.018438,
-.042004,.011316,
-.043331,.003851,
-.043341,-.003732,
-.042034,-.011201,
-.039451,-.018331,
-.035668,-.024903,
-.0356,-.025,
-.03056,-.01996,
270.*
4,1,17,-.01996,.03056,
-.01435,.033562,
-.008304,.035544,
-.002006,.036446,
.004353,.03624,
.01058,.034934,
.016486,.032566,
.01996,.03056,
.025,.0356,
.018438,.0394,
.011316,.042004,
.003851,.043331,
-.003732,.043341,
-.011201,.042034,
-.018331,.039451,
-.024903,.035668,
-.025,.0356,
-.01996,.03056,
270.*
%
%ADD23MACRO23*%
%AMMACRO15*
4,1,17,.03273,.02212,
.036074,.0161,
.038322,.009592,
.039405,.002791,
.039291,-.004094,
.037983,-.010854,
.035521,-.017285,
.03273,-.02212,
.03775,-.02715,
.041891,-.020182,
.044759,-.012601,
.046267,-.004638,
.04637,.003467,
.045063,.011466,
.042388,.019117,
.038424,.026188,
.03775,.02715,
.03273,.02212,
180.*
4,1,17,.02212,-.03273,
.0161,-.036074,
.009592,-.038322,
.002791,-.039405,
-.004094,-.039291,
-.010854,-.037983,
-.017285,-.035521,
-.02212,-.03273,
-.02715,-.03775,
-.020182,-.041891,
-.012601,-.044759,
-.004638,-.046267,
.003467,-.04637,
.011466,-.045063,
.019117,-.042388,
.026188,-.038424,
.02715,-.03775,
.02212,-.03273,
180.*
4,1,17,-.03273,-.02212,
-.036074,-.0161,
-.038322,-.009592,
-.039405,-.002791,
-.039291,.004094,
-.037983,.010854,
-.035521,.017285,
-.03273,.02212,
-.03775,.02715,
-.041891,.020182,
-.044759,.012601,
-.046267,.004638,
-.04637,-.003467,
-.045063,-.011466,
-.042388,-.019117,
-.038424,-.026188,
-.03775,-.02715,
-.03273,-.02212,
180.*
4,1,17,-.02212,.03273,
-.0161,.036074,
-.009592,.038322,
-.002791,.039405,
.004094,.039291,
.010854,.037983,
.017285,.035521,
.02212,.03273,
.02715,.03775,
.020182,.041891,
.012601,.044759,
.004638,.046267,
-.003467,.04637,
-.011466,.045063,
-.019117,.042388,
-.026188,.038424,
-.02715,.03775,
-.02212,.03273,
180.*
%
%ADD15MACRO15*%
%ADD43C,.006*%
%ADD45C,.22034*%
%ADD54C,.24506*%
%ADD53O,.24504X.28404*%
%ADD52C,.13238*%
%ADD49C,.16406*%
%ADD51C,.12717*%
%ADD46C,.13266*%
%ADD50C,.15806*%
%ADD47C,.35606*%
%ADD44C,.24475*%
%ADD48C,.19786*%
G75*
%LPD*%
G75*
G36*
G01X-723776Y-489221D02*
X1782976D01*
Y2987387D01*
X-723776D01*
Y-489221D01*
G37*
%LPC*%
G75*
G36*
G01X397638Y2084610D02*
G02X403508Y2078740I0J-5870D01*
G01Y7874D01*
G02X397638Y2004I-5870J0D01*
G01X104331D01*
G02X100429Y5906I0J3902D01*
G01Y9843D01*
G03X92520Y17752I-7909J0D01*
G01X5906D01*
G02X2004Y21654I0J3902D01*
G01Y2064961D01*
G02X5905Y2068862I3901J0D01*
G01X92520D01*
G03X100429Y2076772I0J7909D01*
G01Y2080709D01*
G02X104331Y2084610I3902J-1D01*
G01X397638D01*
G37*
%LPD*%
G75*
G36*
G01X17976Y989245D02*
Y990190D01*
G02X22970Y990185I2491J-5857D01*
G01Y989240D01*
G03X23209Y988813I500J0D01*
G02X23856Y988346I-2741J-4480D01*
G01X25407D01*
G02X14103Y984333I-4940J-4013D01*
G02X15503Y988316I6365J0D01*
G01X17045D01*
G02X17736Y988818I3422J-3984D01*
G03X17976Y989245I-260J427D01*
G37*
G36*
G01X17980Y1347510D02*
Y1348455D01*
G02X22974Y1348450I2491J-5857D01*
G01Y1347505D01*
G03X23213Y1347078I500J0D01*
G02X23859Y1346612I-2741J-4480D01*
G01X25411D01*
G02X14107Y1342598I-4939J-4014D01*
G02X15507Y1346580I6365J-1D01*
G01X17048D01*
G02X17740Y1347083I3424J-3982D01*
G03X17980Y1347510I-260J427D01*
G37*
G54D45*
X370567Y1882819D03*
G54D54*
X307086Y308267D03*
G54D53*
Y1883071D03*
G54D52*
X163385Y27205D03*
Y202205D03*
Y377205D03*
X163386Y552205D03*
Y727205D03*
X163385Y902205D03*
Y1077205D03*
Y1252205D03*
Y1427205D03*
Y1602205D03*
Y1777205D03*
Y1952205D03*
G54D49*
X57735Y2026661D03*
Y1922291D03*
Y390834D03*
Y268811D03*
Y181976D03*
Y59953D03*
X12735Y2026661D03*
Y1922291D03*
Y390834D03*
Y268811D03*
Y181976D03*
Y59953D03*
G54D51*
X20472Y1054606D03*
G54D46*
X373385Y1957520D03*
Y1782520D03*
Y1607520D03*
Y1432520D03*
Y1257520D03*
Y1082520D03*
Y907520D03*
X373386Y732520D03*
Y557520D03*
X373385Y382520D03*
Y207520D03*
Y32520D03*
G54D50*
X58995Y1587992D03*
Y543701D03*
X13995Y1587992D03*
Y543701D03*
G54D47*
X359842Y2003780D03*
Y1828779D03*
Y1653780D03*
Y1478780D03*
Y1303780D03*
Y1128779D03*
Y953780D03*
Y778780D03*
Y603779D03*
Y428779D03*
Y253780D03*
Y78780D03*
G54D44*
X370078Y308268D03*
G54D48*
X307087Y2043503D03*
X307086Y1693504D03*
Y1343504D03*
Y827165D03*
Y477165D03*
Y127165D03*
X65354Y1864960D03*
Y1514960D03*
Y1164960D03*
Y814960D03*
Y464960D03*
Y114960D03*
G54D26*
X48433Y866179D03*
X48467Y869278D03*
X49441Y1238962D03*
X46980Y1335843D03*
Y1325843D03*
Y1315843D03*
Y1320843D03*
Y1330843D03*
Y1345843D03*
Y1340843D03*
X57124Y675327D03*
X54483Y679810D03*
X59236Y670758D03*
X70865Y854278D03*
Y872278D03*
Y866278D03*
Y860278D03*
Y897750D03*
Y890116D03*
X60815Y1019026D03*
X63577Y1019115D03*
X59127Y1257647D03*
X58356Y1279812D03*
X58416Y1272383D03*
X61866Y1309190D03*
X67568Y1307829D03*
X54543Y1308995D03*
X61866Y1342104D03*
X93223Y417736D03*
X94347Y421562D03*
X95775Y751469D03*
X92216Y899865D03*
X90708Y878615D03*
X92633Y907404D03*
X92989Y927334D03*
X98139Y990959D03*
X76446Y1014871D03*
X79499D03*
X82763Y1060051D03*
X96684Y1081791D03*
X96510Y1395382D03*
X95236Y1453321D03*
X106958Y26285D03*
X101430Y41803D03*
X107405Y49898D03*
X107037Y34687D03*
X104350Y62293D03*
X107263Y72244D03*
X109054Y58250D03*
X107213Y85169D03*
X106836Y376461D03*
X106709Y391219D03*
X105451Y406795D03*
X114498Y396207D03*
X109475Y434743D03*
X111017Y419566D03*
X107025Y725368D03*
X105087Y754126D03*
X106935Y745139D03*
X107173Y735219D03*
X112836Y769122D03*
X113697Y794293D03*
X105395Y972040D03*
X102611Y972220D03*
X100687Y999391D03*
X107351Y1093484D03*
X107235Y1081791D03*
X107215Y1072208D03*
X108779Y1105760D03*
X105152Y1118381D03*
X112503Y1115860D03*
X108468Y1129286D03*
X100719Y1312810D03*
Y1306810D03*
Y1330810D03*
Y1336810D03*
Y1324810D03*
Y1318810D03*
Y1346065D03*
X101626Y1397635D03*
X106962Y1434041D03*
X106921Y1419492D03*
X106763Y1444599D03*
X107006Y1452651D03*
X108574Y1463389D03*
X113518Y1489571D03*
X107355Y1770437D03*
X107391Y1794460D03*
X107220Y1791589D03*
X107373Y1780544D03*
X108819Y1812118D03*
X106819Y1802230D03*
X108819Y1824470D03*
X144878Y1738861D03*
X157558Y51426D03*
X161339Y88108D03*
X159417Y91281D03*
X158901Y85017D03*
X156865Y401207D03*
X161517Y436119D03*
X159019Y439268D03*
X158807Y432969D03*
X156610Y751063D03*
X158956Y780982D03*
X161479Y784141D03*
X159053Y787280D03*
X156854Y1101031D03*
X159382Y1136151D03*
X158456Y1129045D03*
X158618Y1399448D03*
X164037Y1400226D03*
X170351Y1401324D03*
X159192Y1451105D03*
X159216Y1477124D03*
X159526Y1483434D03*
X150309Y1737009D03*
X168151Y1739208D03*
X156183Y1735240D03*
X165782Y1732903D03*
X163257Y1737619D03*
X156452Y1800821D03*
X161844Y1828225D03*
X159822Y1831380D03*
X159075Y1825087D03*
X175989Y944537D03*
X176011Y936829D03*
X175359Y963486D03*
X175561Y955964D03*
X175135Y972490D03*
X175022Y980281D03*
X175742Y989958D03*
X175449Y997660D03*
X175698Y1008730D03*
X175473Y1016296D03*
X175448Y1031766D03*
X175897Y1023997D03*
X176083Y1402321D03*
X173394Y1736051D03*
X256947Y128276D03*
X257125Y115559D03*
X265722Y463102D03*
X265737Y473680D03*
X255837Y823626D03*
X255687Y812192D03*
X280240Y1858668D03*
X279976Y1864565D03*
X308057Y248863D03*
X306267Y241010D03*
X314914Y238162D03*
X314940Y252083D03*
X305867Y258589D03*
X309678Y1053262D03*
X312527Y1162266D03*
X312698Y1172804D03*
X314183Y1403423D03*
X302267Y1524401D03*
X301734Y1513883D03*
X312077Y1575871D03*
X311539Y1753499D03*
X292614Y1864565D03*
X331403Y51409D03*
X333889Y56021D03*
X338227Y61559D03*
X320372Y225979D03*
X318088Y231820D03*
X321899Y238137D03*
X329930Y245684D03*
X331046Y232021D03*
X320961Y250105D03*
X324709Y231580D03*
X335522Y404033D03*
X323313Y418313D03*
X326196Y413982D03*
X328950Y409216D03*
X320980Y423225D03*
X336617Y577978D03*
X319305Y582111D03*
X329636Y584715D03*
X317724Y588250D03*
X337387Y586230D03*
X320380Y576491D03*
X331867Y589810D03*
X333750Y595326D03*
X323751Y589155D03*
X319852Y593330D03*
X321742Y599041D03*
X331568Y752967D03*
X339012Y752859D03*
X329336Y762693D03*
X334010Y758588D03*
X327524Y758020D03*
X339615Y926357D03*
X329938Y948756D03*
X332527Y943746D03*
X324098Y946104D03*
X318557Y941178D03*
X323868Y929978D03*
X326646Y939788D03*
X333300Y928464D03*
X336160Y937262D03*
X328583Y933262D03*
X321425Y951577D03*
X324246Y1051786D03*
X335677Y1048904D03*
X317592Y1053050D03*
X331920Y1116088D03*
X337509Y1109598D03*
X328989Y1121090D03*
X326558Y1126368D03*
X323403Y1172804D03*
X327452Y1279447D03*
X321978Y1282086D03*
X338047Y1282599D03*
X333242Y1276809D03*
X329619Y1284016D03*
X327932Y1289221D03*
X319404Y1401346D03*
X325636Y1399114D03*
X334646Y1400804D03*
X323720Y1570924D03*
X329399Y1571939D03*
X317243Y1574832D03*
X333474Y1566686D03*
X335963Y1573797D03*
X329887Y1752081D03*
X321283Y1753466D03*
X335730Y1753270D03*
X338309Y1927623D03*
X332399Y1926787D03*
X359931Y52189D03*
X348289Y50863D03*
X345089Y56190D03*
X340373Y51579D03*
X342097Y401684D03*
X363825Y401768D03*
X342900Y580126D03*
X362577Y752783D03*
X344109Y751809D03*
X343656Y933725D03*
X345578Y1047844D03*
X344099Y1106798D03*
X349855Y1104302D03*
X344130Y1401670D03*
X350690Y1403243D03*
X348710Y1570187D03*
X361011Y1568890D03*
X343402Y1572080D03*
X348245Y1575241D03*
X355364Y1570990D03*
X345537Y1916558D03*
X344402Y1911123D03*
X363361Y1918313D03*
X358318Y1920680D03*
X363411Y1923459D03*
X340336Y1922409D03*
X347676Y1922165D03*
X372204Y56126D03*
X365720Y52336D03*
X379257Y52158D03*
X379572Y58441D03*
X387524Y76847D03*
X374442Y406857D03*
X380619Y410112D03*
X380878Y403999D03*
X374542Y401282D03*
X368907Y404308D03*
X376654Y754748D03*
X382892Y767710D03*
X386790Y774338D03*
X380186Y761742D03*
X379335Y1189778D03*
X383276Y1184136D03*
X386816Y1179841D03*
X376472Y1194999D03*
X373674Y1199967D03*
X371523Y1204725D03*
X367829Y1566108D03*
X374775Y1919243D03*
X379403Y1917261D03*
X369748Y1921795D03*
X391278Y765894D03*
G54D34*
X165975Y265783D03*
Y296140D03*
Y286803D03*
Y276298D03*
Y312307D03*
Y303868D03*
X157272Y604773D03*
Y633416D03*
Y613574D03*
Y624079D03*
Y641144D03*
Y649583D03*
X166699Y972924D03*
Y983439D03*
Y993944D03*
X166424Y1011298D03*
Y1003570D03*
Y1019737D03*
X155749Y1307733D03*
Y1328753D03*
Y1318248D03*
Y1354257D03*
Y1338090D03*
Y1345818D03*
X158492Y1667763D03*
Y1657248D03*
Y1695333D03*
Y1687605D03*
Y1678268D03*
Y1703772D03*
X219214Y1287272D03*
Y1301975D03*
X219349Y1308924D03*
X219214Y1294491D03*
X219178Y1324285D03*
Y1332321D03*
Y1316842D03*
Y1339840D03*
X243741Y153964D03*
X222732D03*
X232700D03*
X243741Y170131D03*
Y161692D03*
X222732Y170131D03*
Y161692D03*
X232700Y170131D03*
Y161692D03*
X239746Y407393D03*
Y396878D03*
Y417898D03*
X243980Y754782D03*
X234012D03*
X243980Y762510D03*
Y770949D03*
X234012Y762510D03*
Y770949D03*
X226642Y1287272D03*
Y1301975D03*
X235465D03*
X226777Y1308924D03*
X235600D03*
X242961Y1301975D03*
X243096Y1308924D03*
X226642Y1294491D03*
X235465D03*
X242961D03*
X226606Y1324285D03*
X235429D03*
X226606Y1332321D03*
X235429D03*
X242925Y1324285D03*
Y1332321D03*
X226606Y1316842D03*
X235429D03*
X242925D03*
X226606Y1339840D03*
X235429D03*
X242925D03*
X224573Y2031480D03*
X234541D03*
X224573Y2020965D03*
X234541D03*
X224573Y2059050D03*
X234541Y2051322D03*
Y2059050D03*
X224573Y2041985D03*
Y2051322D03*
X234541Y2041985D03*
Y2067489D03*
X224573D03*
X256566Y54944D03*
X264104D03*
X256566Y45572D03*
X264104D03*
X256566Y65449D03*
X264104D03*
X264861Y153964D03*
X253083D03*
X264861Y170131D03*
Y161692D03*
X253083Y170131D03*
Y161692D03*
X264596Y221664D03*
X252818D03*
X264596Y242684D03*
Y232179D03*
X252818Y242684D03*
Y232179D03*
X264596Y268188D03*
Y259749D03*
Y252021D03*
X252818Y268188D03*
Y252021D03*
Y259749D03*
X266040Y407146D03*
Y396631D03*
Y417651D03*
X257572Y396630D03*
Y407145D03*
X248714Y407536D03*
Y397021D03*
X257572Y417650D03*
X248714Y418041D03*
X267166Y581440D03*
Y572639D03*
Y609010D03*
Y601282D03*
Y591945D03*
Y617449D03*
X255021Y754782D03*
Y762510D03*
Y770949D03*
X263174Y855159D03*
Y862887D03*
X251396D03*
Y855159D03*
Y871326D03*
X263174D03*
X262766Y949344D03*
Y967106D03*
Y959859D03*
X262621Y974386D03*
Y990553D03*
Y982114D03*
X261219Y1124364D03*
Y1134879D03*
X251251Y1124364D03*
Y1134879D03*
X261219Y1145384D03*
X251251D03*
X259581Y1272430D03*
Y1282945D03*
Y1293450D03*
Y1302787D03*
Y1310515D03*
Y1318954D03*
X263939Y1548010D03*
Y1534139D03*
Y1541055D03*
X261564Y1621823D03*
Y1642843D03*
Y1632338D03*
Y1668347D03*
Y1659908D03*
Y1652180D03*
X265759Y1697613D03*
X254718D03*
X265759Y1676593D03*
Y1687108D03*
X254718D03*
Y1676593D03*
X254457Y1722140D03*
X265498D03*
X265759Y1714678D03*
X254718D03*
Y1706950D03*
X265759D03*
X258639Y1819074D03*
Y1812119D03*
Y1805203D03*
X250468Y1819074D03*
Y1812119D03*
Y1805203D03*
X267396Y1819077D03*
Y1805206D03*
Y1812122D03*
X258459Y1826219D03*
X250288D03*
X267037Y1826222D03*
X258459Y1840090D03*
Y1833135D03*
X267037Y1833138D03*
Y1840093D03*
X250288Y1833135D03*
Y1840090D03*
X245582Y2031480D03*
Y2020965D03*
X258337D03*
Y2031480D03*
X245582Y2041985D03*
Y2051322D03*
Y2059050D03*
X258337Y2051322D03*
Y2059050D03*
Y2041985D03*
Y2067489D03*
X245582D03*
X288102Y54944D03*
Y45572D03*
X271572Y54944D03*
X279754D03*
X271572Y45572D03*
X279754D03*
X288102Y65449D03*
X271572D03*
X279754D03*
X274531Y407289D03*
Y396774D03*
Y417794D03*
X278944Y581440D03*
Y572639D03*
Y601282D03*
Y609010D03*
Y591945D03*
Y617449D03*
X274544Y949344D03*
Y967106D03*
Y959859D03*
X274399Y974386D03*
Y990553D03*
Y982114D03*
X279015Y1124077D03*
X288363Y1123935D03*
X279015Y1134592D03*
X288363Y1134450D03*
X269975Y1134735D03*
Y1124220D03*
X288363Y1144955D03*
X279015Y1145097D03*
X269975Y1145240D03*
X286721Y1184312D03*
Y1192040D03*
X278182Y1184455D03*
Y1192183D03*
X286721Y1200479D03*
X278182Y1200622D03*
X270622Y1282945D03*
Y1272430D03*
Y1293450D03*
Y1302787D03*
Y1310515D03*
Y1318954D03*
X278400Y1548190D03*
X271534Y1548010D03*
X285995Y1548190D03*
X278400Y1534319D03*
Y1541235D03*
X271534Y1534139D03*
Y1541055D03*
X285995Y1534319D03*
Y1541235D03*
X273342Y1621823D03*
Y1642843D03*
Y1632338D03*
Y1668347D03*
Y1652180D03*
Y1659908D03*
X270115Y2031480D03*
Y2020965D03*
Y2051322D03*
Y2059050D03*
Y2041985D03*
Y2067489D03*
X300537Y516309D03*
X307966Y516419D03*
Y524147D03*
X300537Y524037D03*
Y532476D03*
X307966Y532586D03*
X292569Y524323D03*
Y516595D03*
Y532762D03*
X315187Y652457D03*
Y661258D03*
X304146D03*
Y652457D03*
Y681100D03*
X315187D03*
Y671763D03*
X304146D03*
X315187Y688828D03*
X304146D03*
Y697267D03*
X315187D03*
X307194Y1020657D03*
X307078Y1007303D03*
X307274Y1001286D03*
X307143Y1014094D03*
X307129Y1027081D03*
X306999Y1033718D03*
X303159Y1184526D03*
Y1192254D03*
X311936Y1192253D03*
Y1184525D03*
X294691Y1184526D03*
Y1192254D03*
X311936Y1200692D03*
X303159Y1200693D03*
X294691D03*
X309823Y1472957D03*
X309464Y1480102D03*
X309823Y1466002D03*
Y1459086D03*
X292715Y1480099D03*
X292895Y1472954D03*
X301066D03*
X300886Y1480099D03*
X292895Y1459083D03*
Y1465999D03*
X301066D03*
Y1459083D03*
X309464Y1493973D03*
Y1487018D03*
X292715Y1487015D03*
Y1493970D03*
X300886D03*
Y1487015D03*
X292754Y1917148D03*
X300349D03*
X292754Y1910232D03*
X300349D03*
X307215Y1910412D03*
X314810D03*
Y1917328D03*
X307215D03*
X292754Y1924103D03*
X300349D03*
X314810Y1924283D03*
X307215D03*
X332775Y318634D03*
X332693Y311980D03*
X332775Y335272D03*
Y342461D03*
Y325935D03*
X332685Y348655D03*
X325139Y516632D03*
Y524360D03*
X316791Y524432D03*
Y516704D03*
Y532871D03*
X325139Y532799D03*
X318235Y1020657D03*
X318315Y1001286D03*
X318119Y1007303D03*
X318184Y1014094D03*
X318170Y1027081D03*
X318040Y1033718D03*
X343816Y318634D03*
X343734Y311980D03*
X343816Y335272D03*
Y342461D03*
Y325935D03*
X343726Y348655D03*
G54D38*
X253385Y21890D03*
Y32520D03*
X263385Y21890D03*
Y32520D03*
X253385Y196890D03*
X263385D03*
X253385Y207520D03*
X263385D03*
X253385Y371890D03*
X263385D03*
X253385Y382520D03*
X263385D03*
X253386Y546890D03*
Y557520D03*
X263386Y546890D03*
Y557520D03*
X253386Y721890D03*
Y732520D03*
X263386Y721890D03*
Y732520D03*
X253385Y896890D03*
X263385D03*
X253385Y907520D03*
X263385D03*
X253385Y1071890D03*
X263385D03*
X253385Y1082520D03*
X263385D03*
X253385Y1246890D03*
Y1257520D03*
X263385Y1246890D03*
Y1257520D03*
X253385Y1421890D03*
Y1432520D03*
X263385Y1421890D03*
Y1432520D03*
X253385Y1596890D03*
X263385D03*
X253385Y1607520D03*
X263385D03*
X253385Y1771890D03*
X263385D03*
X253385Y1782520D03*
X263385D03*
X253385Y1946890D03*
Y1957520D03*
X263385Y1946890D03*
Y1957520D03*
X273385Y21890D03*
Y32520D03*
X283385Y21890D03*
Y32520D03*
X273385Y196890D03*
X283385D03*
X273385Y207520D03*
X283385D03*
X273385Y371890D03*
X283385D03*
X273385Y382520D03*
X283385D03*
X273386Y546890D03*
Y557520D03*
X283386Y546890D03*
Y557520D03*
X273386Y721890D03*
Y732520D03*
X283386Y721890D03*
Y732520D03*
X273385Y896890D03*
X283385D03*
X273385Y907520D03*
X283385D03*
X273385Y1071890D03*
X283385D03*
X273385Y1082520D03*
X283385D03*
X273385Y1246890D03*
Y1257520D03*
X283385Y1246890D03*
Y1257520D03*
X273385Y1421890D03*
Y1432520D03*
X283385Y1421890D03*
Y1432520D03*
X273385Y1596890D03*
X283385D03*
X273385Y1607520D03*
X283385D03*
X273385Y1771890D03*
X283385D03*
X273385Y1782520D03*
X283385D03*
X273385Y1946890D03*
Y1957520D03*
X283385Y1946890D03*
Y1957520D03*
X293385Y21890D03*
Y32520D03*
X303385Y21890D03*
Y32520D03*
X313385D03*
Y21890D03*
X293385Y196890D03*
X303385D03*
X313385D03*
X293385Y207520D03*
X303385D03*
X313385D03*
X293385Y371890D03*
X303385D03*
X313385D03*
X293385Y382520D03*
X303385D03*
X313385D03*
X293386Y546890D03*
Y557520D03*
X303386Y546890D03*
Y557520D03*
X313386D03*
Y546890D03*
X293386Y721890D03*
Y732520D03*
X303386Y721890D03*
Y732520D03*
X313386D03*
Y721890D03*
X293385Y896890D03*
X303385D03*
X313385D03*
X293385Y907520D03*
X303385D03*
X313385D03*
X293385Y1071890D03*
X303385D03*
X313385D03*
X293385Y1082520D03*
X303385D03*
X313385D03*
X293385Y1246890D03*
Y1257520D03*
X303385Y1246890D03*
Y1257520D03*
X313385D03*
Y1246890D03*
X293385Y1421890D03*
Y1432520D03*
X303385Y1421890D03*
Y1432520D03*
X313385D03*
Y1421890D03*
X293385Y1596890D03*
X303385D03*
X313385D03*
X293385Y1607520D03*
X303385D03*
X313385D03*
X293385Y1771890D03*
X303385D03*
X313385D03*
X293385Y1782520D03*
X303385D03*
X313385D03*
X293385Y1946890D03*
Y1957520D03*
X303385Y1946890D03*
Y1957520D03*
X313385D03*
Y1946890D03*
X337165Y24705D03*
X323385Y32520D03*
Y21890D03*
X337165Y34705D03*
Y199705D03*
X323385Y196890D03*
X337165Y209705D03*
X323385Y207520D03*
Y371890D03*
X337165Y374705D03*
Y384705D03*
X323385Y382520D03*
X337166Y549705D03*
Y559705D03*
X323386Y557520D03*
Y546890D03*
X337166Y724705D03*
X323386Y732520D03*
Y721890D03*
X337166Y734705D03*
X337165Y899705D03*
X323385Y896890D03*
X337165Y909705D03*
X323385Y907520D03*
Y1071890D03*
X337165Y1074705D03*
Y1084705D03*
X323385Y1082520D03*
X337165Y1249705D03*
Y1259705D03*
X323385Y1257520D03*
Y1246890D03*
X337165Y1424705D03*
Y1434705D03*
X323385Y1432520D03*
Y1421890D03*
X337165Y1599705D03*
X323385Y1596890D03*
X337165Y1609705D03*
X323385Y1607520D03*
Y1771890D03*
X337165Y1774705D03*
Y1784705D03*
X323385Y1782520D03*
X337165Y1949705D03*
Y1959705D03*
X323385Y1957520D03*
Y1946890D03*
X342165Y19705D03*
Y29705D03*
X347165Y24705D03*
X352165Y19705D03*
Y29705D03*
X357165Y24705D03*
X362165Y19705D03*
Y29705D03*
X347165Y34705D03*
X357165D03*
X342165Y194705D03*
X347165Y199705D03*
X352165Y194705D03*
X357165Y199705D03*
X362165Y194705D03*
X342165Y204705D03*
X347165Y209705D03*
X352165Y204705D03*
X357165Y209705D03*
X362165Y204705D03*
X342165Y369705D03*
X352165D03*
X362165D03*
X342165Y379705D03*
X347165Y374705D03*
Y384705D03*
X352165Y379705D03*
X357165Y374705D03*
Y384705D03*
X362165Y379705D03*
X342166Y544705D03*
Y554705D03*
X347166Y549705D03*
Y559705D03*
X352166Y544705D03*
Y554705D03*
X357166Y549705D03*
Y559705D03*
X362166Y544705D03*
Y554705D03*
X342166Y719705D03*
Y729705D03*
X347166Y724705D03*
X352166Y719705D03*
Y729705D03*
X357166Y724705D03*
X362166Y719705D03*
Y729705D03*
X347166Y734705D03*
X357166D03*
X342165Y894705D03*
X347165Y899705D03*
X352165Y894705D03*
X357165Y899705D03*
X362165Y894705D03*
X342165Y904705D03*
X347165Y909705D03*
X352165Y904705D03*
X357165Y909705D03*
X362165Y904705D03*
X342165Y1069705D03*
X352165D03*
X362165D03*
X342165Y1079705D03*
X347165Y1074705D03*
Y1084705D03*
X352165Y1079705D03*
X357165Y1074705D03*
Y1084705D03*
X362165Y1079705D03*
X342165Y1244705D03*
Y1254705D03*
X347165Y1249705D03*
Y1259705D03*
X352165Y1244705D03*
Y1254705D03*
X357165Y1249705D03*
Y1259705D03*
X362165Y1244705D03*
Y1254705D03*
X342165Y1419705D03*
Y1429705D03*
X347165Y1424705D03*
Y1434705D03*
X352165Y1419705D03*
Y1429705D03*
X357165Y1424705D03*
Y1434705D03*
X362165Y1419705D03*
Y1429705D03*
X342165Y1594705D03*
X347165Y1599705D03*
X352165Y1594705D03*
X357165Y1599705D03*
X362165Y1594705D03*
X342165Y1604705D03*
X347165Y1609705D03*
X352165Y1604705D03*
X357165Y1609705D03*
X362165Y1604705D03*
X342165Y1769705D03*
X352165D03*
X362165D03*
X342165Y1779705D03*
X347165Y1774705D03*
Y1784705D03*
X352165Y1779705D03*
X357165Y1774705D03*
Y1784705D03*
X362165Y1779705D03*
X342165Y1944705D03*
Y1954705D03*
X347165Y1949705D03*
Y1959705D03*
X352165Y1944705D03*
Y1954705D03*
X357165Y1949705D03*
Y1959705D03*
X362165Y1944705D03*
Y1954705D03*
G54D17*
X9606Y599901D03*
Y627264D03*
Y1471949D03*
Y1499311D03*
G54D27*
X65354Y101180D03*
X55511Y105117D03*
X51574Y114960D03*
X55511Y124803D03*
X65354Y128740D03*
Y451180D03*
X55511Y455117D03*
X51574Y464960D03*
X55511Y474803D03*
X65354Y478740D03*
Y801180D03*
X55511Y805117D03*
X51574Y814960D03*
X55511Y824803D03*
X65354Y828740D03*
Y1151180D03*
X55511Y1155117D03*
X51574Y1164960D03*
X55511Y1174803D03*
X65354Y1178740D03*
Y1501180D03*
X55511Y1505117D03*
X51574Y1514960D03*
X55511Y1524803D03*
X65354Y1528740D03*
Y1851180D03*
X55511Y1855117D03*
X51574Y1864960D03*
X55511Y1874803D03*
X65354Y1878740D03*
X75197Y105117D03*
Y124803D03*
X79134Y114960D03*
Y464960D03*
X75197Y455117D03*
Y474803D03*
Y805117D03*
Y824803D03*
X79134Y814960D03*
Y1164960D03*
X75197Y1155117D03*
Y1174803D03*
Y1505117D03*
Y1524803D03*
X79134Y1514960D03*
Y1864960D03*
X75197Y1855117D03*
Y1874803D03*
X307086Y113385D03*
X297243Y117322D03*
X293306Y127165D03*
X297243Y137008D03*
X307086Y140945D03*
Y463385D03*
X297243Y467322D03*
X293306Y477165D03*
X297243Y487008D03*
X307086Y490945D03*
Y813385D03*
X297243Y817322D03*
X293306Y827165D03*
X297243Y837008D03*
X307086Y840945D03*
Y1329724D03*
X297243Y1333661D03*
X293306Y1343504D03*
X297243Y1353347D03*
X307086Y1357284D03*
Y1679724D03*
X297243Y1683661D03*
X293306Y1693504D03*
X297243Y1703347D03*
X307086Y1707284D03*
X307087Y2029723D03*
X297244Y2033660D03*
X293307Y2043503D03*
X297244Y2053346D03*
X307087Y2057283D03*
X320866Y127165D03*
X316929Y117322D03*
Y137008D03*
Y467322D03*
Y487008D03*
X320866Y477165D03*
Y827165D03*
X316929Y817322D03*
Y837008D03*
Y1333661D03*
Y1353347D03*
X320866Y1343504D03*
Y1693504D03*
X316929Y1683661D03*
Y1703347D03*
X316930Y2033660D03*
Y2053346D03*
X320867Y2043503D03*
G54D29*
X119920Y18071D03*
Y28071D03*
Y38071D03*
Y48071D03*
Y58071D03*
Y68071D03*
Y78071D03*
Y88071D03*
Y218071D03*
Y228071D03*
Y238071D03*
Y248071D03*
Y258071D03*
Y268071D03*
Y278071D03*
Y288071D03*
Y298071D03*
Y308071D03*
Y318071D03*
Y328071D03*
Y366102D03*
Y376102D03*
Y386102D03*
Y396102D03*
Y406102D03*
Y416102D03*
Y426102D03*
Y436102D03*
Y566102D03*
Y576102D03*
Y586102D03*
Y596102D03*
Y606102D03*
Y616102D03*
Y626102D03*
Y636102D03*
Y646102D03*
Y656102D03*
Y666102D03*
Y676102D03*
Y714134D03*
Y724134D03*
Y734134D03*
Y744134D03*
Y754134D03*
Y764134D03*
Y774134D03*
Y784134D03*
Y914134D03*
Y924134D03*
Y934134D03*
Y944134D03*
Y954134D03*
Y964134D03*
Y974134D03*
Y984134D03*
Y994134D03*
Y1004134D03*
Y1014134D03*
Y1024134D03*
Y1062165D03*
Y1072165D03*
Y1082165D03*
Y1092165D03*
Y1102165D03*
Y1112165D03*
Y1122165D03*
Y1132165D03*
Y1262165D03*
Y1272165D03*
Y1282165D03*
Y1292165D03*
Y1302165D03*
Y1312165D03*
Y1322165D03*
Y1332165D03*
Y1342165D03*
Y1352165D03*
Y1362165D03*
Y1372165D03*
Y1410197D03*
Y1420197D03*
Y1430197D03*
Y1440197D03*
Y1450197D03*
Y1460197D03*
Y1470197D03*
Y1480197D03*
Y1610197D03*
Y1620197D03*
Y1630197D03*
Y1640197D03*
Y1650197D03*
Y1660197D03*
Y1670197D03*
Y1680197D03*
Y1690197D03*
Y1700197D03*
Y1710197D03*
Y1720197D03*
Y1758228D03*
Y1768228D03*
Y1778228D03*
Y1788228D03*
Y1798228D03*
Y1808228D03*
Y1818228D03*
Y1828228D03*
Y1958228D03*
Y1968228D03*
Y1978228D03*
Y1988228D03*
Y1998228D03*
Y2008228D03*
Y2018228D03*
Y2028228D03*
Y2038228D03*
Y2048228D03*
Y2058228D03*
Y2068228D03*
X139920Y28071D03*
Y18071D03*
Y58071D03*
Y48071D03*
Y38071D03*
Y78071D03*
Y68071D03*
Y88071D03*
Y228071D03*
Y218071D03*
Y248071D03*
Y238071D03*
Y268071D03*
Y258071D03*
Y298071D03*
Y288071D03*
Y278071D03*
Y318071D03*
Y308071D03*
Y328071D03*
Y366102D03*
Y396102D03*
Y386102D03*
Y376102D03*
Y416102D03*
Y406102D03*
Y436102D03*
Y426102D03*
Y566102D03*
Y586102D03*
Y576102D03*
Y606102D03*
Y596102D03*
Y636102D03*
Y626102D03*
Y616102D03*
Y656102D03*
Y646102D03*
Y676102D03*
Y666102D03*
Y734134D03*
Y724134D03*
Y714134D03*
Y754134D03*
Y744134D03*
Y774134D03*
Y764134D03*
Y784134D03*
Y924134D03*
Y914134D03*
Y944134D03*
Y934134D03*
Y974134D03*
Y964134D03*
Y954134D03*
Y994134D03*
Y984134D03*
Y1024134D03*
Y1014134D03*
Y1004134D03*
Y1072165D03*
Y1062165D03*
Y1092165D03*
Y1082165D03*
Y1122165D03*
Y1112165D03*
Y1102165D03*
Y1132165D03*
Y1262165D03*
Y1282165D03*
Y1272165D03*
Y1312165D03*
Y1302165D03*
Y1292165D03*
Y1332165D03*
Y1322165D03*
Y1362165D03*
Y1352165D03*
Y1342165D03*
Y1372165D03*
Y1410197D03*
Y1430197D03*
Y1420197D03*
Y1460197D03*
Y1450197D03*
Y1440197D03*
Y1480197D03*
Y1470197D03*
Y1620197D03*
Y1610197D03*
Y1650197D03*
Y1640197D03*
Y1630197D03*
Y1670197D03*
Y1660197D03*
Y1700197D03*
Y1690197D03*
Y1680197D03*
Y1720197D03*
Y1710197D03*
Y1768228D03*
Y1758228D03*
Y1798228D03*
Y1788228D03*
Y1778228D03*
Y1818228D03*
Y1808228D03*
Y1828228D03*
Y1958228D03*
Y1988228D03*
Y1978228D03*
Y1968228D03*
Y2008228D03*
Y1998228D03*
Y2038228D03*
Y2028228D03*
Y2018228D03*
Y2058228D03*
Y2048228D03*
Y2068228D03*
G54D13*
X18995Y508701D03*
X23995Y518701D03*
X21495Y559882D03*
X11692D03*
X21495Y1571811D03*
X11692D03*
X23995Y1622992D03*
X18995Y1612992D03*
X28995Y508701D03*
X38995D03*
X48995D03*
X33995Y518701D03*
X43995D03*
X51495Y559882D03*
Y1571811D03*
X43995Y1622992D03*
X33995D03*
X48995Y1612992D03*
X38995D03*
X28995D03*
X53995Y518701D03*
X61298Y559882D03*
Y1571811D03*
X53995Y1622992D03*
X203542Y73105D03*
X204069Y152050D03*
X204137Y247568D03*
X204597Y331786D03*
X203541Y421732D03*
X204333Y506517D03*
X206668Y598130D03*
X204596Y681645D03*
X205626Y774526D03*
X205386Y856244D03*
X210091Y947202D03*
X209296Y1032544D03*
X205030Y1122856D03*
X205122Y1206233D03*
X205626Y1299104D03*
X204332Y1380966D03*
X203243Y1474162D03*
X204859Y1557277D03*
X205923Y1648177D03*
X205387Y1731351D03*
X205310Y1823227D03*
X204069Y1900420D03*
X205905Y1998730D03*
X205310Y2043388D03*
G54D18*
X15547Y707364D03*
X25389D03*
X7673Y703427D03*
X15547Y715238D03*
Y730986D03*
X25389Y715238D03*
Y730986D03*
X7673Y711301D03*
Y719175D03*
Y727049D03*
X15547Y738860D03*
Y754608D03*
X25389Y738860D03*
Y754608D03*
X7673Y742797D03*
Y750671D03*
Y758545D03*
X15547Y762483D03*
Y770357D03*
Y778231D03*
X25389Y762483D03*
Y770357D03*
Y778231D03*
X7673Y774293D03*
Y782167D03*
X15547Y786105D03*
Y801853D03*
X25389Y786105D03*
Y801853D03*
X7673Y790041D03*
Y797915D03*
Y805790D03*
X15547Y809727D03*
Y817601D03*
X25389Y809727D03*
Y817601D03*
X7673Y813664D03*
Y821538D03*
Y829412D03*
X15547Y833349D03*
Y841223D03*
Y849097D03*
X25389Y833349D03*
Y841223D03*
Y849097D03*
X7673Y837286D03*
Y845160D03*
X15547Y856971D03*
Y872719D03*
X25389Y856971D03*
Y864845D03*
X7673Y860908D03*
Y868782D03*
Y876656D03*
X15547Y880593D03*
Y888467D03*
Y896341D03*
X25389Y880593D03*
Y888467D03*
Y896341D03*
X7673Y892404D03*
Y900278D03*
X15547Y912089D03*
Y919963D03*
X25389Y904215D03*
Y919963D03*
X7673Y908152D03*
Y916026D03*
X15547Y927837D03*
Y935711D03*
Y951459D03*
X25389Y927837D03*
Y935711D03*
Y943585D03*
X7673Y931774D03*
Y939648D03*
Y947522D03*
X15547Y959333D03*
Y967207D03*
Y975081D03*
X25389Y959333D03*
Y967207D03*
Y975081D03*
X7673Y955396D03*
Y971144D03*
Y979018D03*
Y994766D03*
X15547Y990829D03*
X25389D03*
Y998703D03*
X7673Y1002640D03*
Y1010514D03*
X15547Y1006577D03*
Y1014451D03*
Y1022325D03*
X25389Y1014451D03*
Y1022325D03*
X7673Y1026262D03*
X15551Y1065629D03*
X25393D03*
X7677Y1061692D03*
X15551Y1073503D03*
Y1081377D03*
X25393D03*
Y1089251D03*
X7677Y1077440D03*
Y1085314D03*
Y1093188D03*
X15551Y1097125D03*
Y1104999D03*
Y1112873D03*
Y1120748D03*
X25393Y1097125D03*
Y1104999D03*
Y1120748D03*
X7677Y1101062D03*
Y1116810D03*
X15551Y1136496D03*
Y1144370D03*
X25393Y1128622D03*
Y1136496D03*
Y1144370D03*
X7677Y1124684D03*
Y1132558D03*
Y1140432D03*
X15551Y1152244D03*
Y1160118D03*
X25393D03*
Y1167992D03*
X7677Y1156180D03*
Y1164055D03*
X15551Y1175866D03*
Y1183740D03*
Y1191614D03*
X25393Y1175866D03*
Y1183740D03*
X7677Y1171929D03*
Y1179803D03*
X15551Y1199488D03*
Y1215236D03*
X25393Y1199488D03*
Y1207362D03*
Y1215236D03*
X7677Y1195551D03*
Y1203425D03*
Y1211299D03*
X15551Y1223110D03*
Y1230984D03*
Y1238858D03*
X25393Y1223110D03*
Y1238858D03*
X7677Y1219173D03*
Y1234921D03*
X15551Y1254606D03*
Y1262480D03*
X25393Y1246732D03*
Y1254606D03*
X7677Y1242795D03*
Y1250669D03*
Y1258543D03*
X15551Y1270354D03*
Y1278228D03*
Y1286102D03*
X25393Y1278228D03*
X7677Y1274291D03*
X15551Y1293976D03*
Y1301850D03*
Y1309724D03*
X25393Y1293976D03*
Y1301850D03*
Y1309724D03*
X7677Y1290039D03*
Y1297913D03*
Y1305787D03*
X15551Y1317598D03*
Y1325472D03*
Y1333346D03*
X25393Y1325472D03*
Y1333346D03*
X7677Y1321535D03*
Y1329409D03*
Y1337283D03*
Y1353031D03*
X15551Y1349094D03*
X25393D03*
Y1356968D03*
X7677Y1368779D03*
Y1384527D03*
X15551Y1372716D03*
Y1380590D03*
X25393Y1364842D03*
Y1380590D03*
Y1388464D03*
X33263Y703427D03*
Y711301D03*
Y719175D03*
Y727049D03*
Y742797D03*
Y750671D03*
Y758545D03*
Y774293D03*
Y782167D03*
Y790041D03*
Y797915D03*
Y805790D03*
Y813664D03*
Y821538D03*
Y829412D03*
Y837286D03*
Y845160D03*
Y860908D03*
Y868782D03*
Y876656D03*
Y884530D03*
Y900278D03*
Y908152D03*
Y916026D03*
Y923900D03*
Y939648D03*
Y947522D03*
Y955396D03*
Y963270D03*
Y979018D03*
Y994766D03*
Y1002640D03*
Y1010514D03*
Y1026262D03*
X33267Y1061692D03*
Y1069566D03*
Y1077440D03*
Y1085314D03*
Y1101062D03*
Y1108936D03*
Y1116810D03*
Y1124684D03*
Y1140432D03*
Y1148306D03*
Y1156180D03*
Y1164055D03*
Y1179803D03*
Y1187677D03*
Y1195551D03*
Y1203425D03*
Y1219173D03*
Y1227047D03*
Y1234921D03*
Y1242795D03*
Y1258543D03*
Y1266417D03*
Y1274291D03*
Y1282165D03*
Y1290039D03*
Y1297913D03*
Y1305787D03*
Y1313661D03*
Y1321535D03*
Y1329409D03*
Y1337283D03*
Y1353031D03*
Y1368779D03*
Y1376653D03*
G54D39*
X287420Y162540D03*
X283086Y162675D03*
X285513Y337688D03*
X281074D03*
X289895D03*
X282776Y512341D03*
X278405D03*
X273938D03*
X269516D03*
X274514Y687192D03*
X270109D03*
X283340D03*
X278955D03*
X276686Y862488D03*
X272181Y862354D03*
X285788Y862237D03*
X281305D03*
X285666Y1031162D03*
X281124D03*
X290107D03*
X289082Y1206777D03*
X284194D03*
X279559D03*
X284240Y1389544D03*
X279518Y1389543D03*
X275052Y1389715D03*
X270579Y1389626D03*
X289675Y1558211D03*
X285054D03*
X274704Y1738196D03*
X279703Y1738398D03*
X284583Y1738465D03*
X289499Y1738735D03*
X287121Y1913327D03*
X282717D03*
X278262D03*
X273817D03*
X296523Y162585D03*
X291943Y162630D03*
X294506Y337688D03*
X294617Y1031162D03*
X293807Y1206777D03*
X298870Y1558211D03*
X294392D03*
G54D10*
X17735Y24953D03*
X27735D03*
X22735Y34953D03*
Y216976D03*
X27735Y206976D03*
X17735D03*
Y233811D03*
X27735D03*
X22735Y243811D03*
X27735Y415834D03*
X17735D03*
X22735Y425834D03*
Y1957291D03*
X27735Y1947291D03*
X17735D03*
X22735Y2061661D03*
X27735Y2051661D03*
X17735D03*
X47735Y24953D03*
X42735Y34953D03*
Y216976D03*
X47735Y206976D03*
X37735Y233811D03*
X47735D03*
X42735Y243811D03*
X47735Y415834D03*
X42735Y425834D03*
X32735D03*
X42735Y1957291D03*
X32735D03*
X47735Y1947291D03*
X42735Y2061661D03*
X32735D03*
X47735Y2051661D03*
X52735Y34953D03*
Y216976D03*
Y243811D03*
Y425834D03*
Y1957291D03*
Y2061661D03*
G54D22*
X23402Y1668874D03*
Y1718480D03*
Y1768087D03*
Y1817693D03*
X45056Y1668874D03*
Y1685410D03*
Y1701945D03*
Y1718480D03*
Y1735016D03*
Y1751551D03*
Y1768087D03*
Y1784622D03*
Y1817693D03*
Y1801158D03*
G54D33*
X166500Y111407D03*
X156430Y461714D03*
X153124Y1169037D03*
X154109Y1499221D03*
X152091Y1866003D03*
X175033Y261594D03*
X231339Y952454D03*
X225131Y1663167D03*
X267433Y624321D03*
X366169Y1360043D03*
Y1376210D03*
Y1367771D03*
G54D35*
X171524Y844722D03*
Y852165D03*
Y860201D03*
Y867720D03*
X169375Y1176256D03*
Y1190335D03*
Y1183740D03*
X169204Y1198253D03*
X170360Y1506440D03*
Y1513924D03*
Y1520519D03*
X170189Y1528437D03*
Y1535880D03*
Y1543916D03*
Y1551435D03*
X168342Y1880706D03*
Y1887301D03*
Y1873222D03*
X168171Y1902662D03*
Y1910698D03*
Y1895219D03*
Y1918217D03*
X179191Y822725D03*
Y830209D03*
X171695Y822725D03*
Y830209D03*
X179191Y836804D03*
X171695D03*
X179020Y844722D03*
Y852165D03*
Y860201D03*
Y867720D03*
X176871Y1176256D03*
Y1190335D03*
Y1183740D03*
X176700Y1198253D03*
X177856Y1506440D03*
Y1513924D03*
Y1520519D03*
X177685Y1528437D03*
Y1535880D03*
Y1543916D03*
Y1551435D03*
X175838Y1880706D03*
Y1887301D03*
Y1873222D03*
X175667Y1902662D03*
Y1910698D03*
Y1895219D03*
Y1918217D03*
X240955Y56999D03*
Y64483D03*
X240784Y78996D03*
X240955Y71078D03*
X240784Y94475D03*
Y101994D03*
Y86439D03*
X236537Y244995D03*
X244033D03*
X236537Y259074D03*
X236366Y266992D03*
Y274435D03*
X244033Y259074D03*
X243862Y266992D03*
Y274435D03*
X236537Y252479D03*
X244033D03*
X236366Y289990D03*
X243862D03*
X236366Y282471D03*
X243862D03*
X241371Y482381D03*
X241200Y490299D03*
X241371Y468302D03*
Y475786D03*
X241200Y513297D03*
Y497742D03*
Y505778D03*
X241382Y1670386D03*
X241211Y1699826D03*
X241382Y1677870D03*
X241211Y1692383D03*
X241382Y1684465D03*
X241211Y1715381D03*
Y1707862D03*
X248451Y56999D03*
Y64483D03*
X248280Y78996D03*
X248451Y71078D03*
X248280Y94475D03*
Y101994D03*
Y86439D03*
X248867Y482381D03*
X248696Y490299D03*
X248867Y468302D03*
Y475786D03*
X248696Y513297D03*
Y497742D03*
Y505778D03*
X254710Y608108D03*
Y601513D03*
Y594029D03*
X247214Y608108D03*
Y601513D03*
Y594029D03*
X254539Y631505D03*
Y623469D03*
Y616026D03*
X247043Y631505D03*
Y623469D03*
Y616026D03*
X254539Y639024D03*
X247043D03*
X255086Y959673D03*
Y973752D03*
Y967157D03*
X247590Y959673D03*
Y973752D03*
Y967157D03*
X254915Y981670D03*
Y997149D03*
Y989113D03*
X247419Y981670D03*
Y997149D03*
Y989113D03*
X254915Y1004668D03*
X247419D03*
X254978Y1215296D03*
X247482D03*
X254978Y1207777D03*
Y1199741D03*
X247482Y1207777D03*
Y1199741D03*
X248878Y1670386D03*
X248707Y1699826D03*
X248878Y1677870D03*
Y1684465D03*
X248707Y1692383D03*
Y1707862D03*
Y1715381D03*
X354391Y1329686D03*
Y1350706D03*
Y1360043D03*
Y1340201D03*
Y1376210D03*
Y1367771D03*
X366169Y1329686D03*
Y1350706D03*
Y1340201D03*
G54D16*
X17480Y599901D03*
Y627264D03*
Y1471949D03*
Y1499311D03*
G54D25*
X32735Y216976D03*
X37735Y206976D03*
Y415834D03*
Y1947291D03*
Y2051661D03*
G54D21*
X5491Y1603149D03*
X67499D03*
G54D41*
X307086Y1883071D03*
G54D19*
X20468Y696341D03*
Y984333D03*
X20472Y1054606D03*
Y1342598D03*
G54D12*
X12735Y59953D03*
Y181976D03*
Y268811D03*
Y390834D03*
Y1922291D03*
Y2026661D03*
X57735Y59953D03*
Y181976D03*
Y268811D03*
Y390834D03*
Y1922291D03*
Y2026661D03*
G54D40*
X307086Y308267D03*
G54D14*
X13995Y543701D03*
Y1587992D03*
X58995Y543701D03*
Y1587992D03*
G54D31*
X163385Y27205D03*
Y202205D03*
Y377205D03*
X163386Y552205D03*
Y727205D03*
X163385Y902205D03*
Y1077205D03*
Y1252205D03*
Y1427205D03*
Y1602205D03*
Y1777205D03*
Y1952205D03*
X373385Y32520D03*
Y207520D03*
Y382520D03*
X373386Y557520D03*
Y732520D03*
X373385Y907520D03*
Y1082520D03*
Y1257520D03*
Y1432520D03*
Y1607520D03*
Y1782520D03*
Y1957520D03*
G54D42*
X359842Y78780D03*
Y253780D03*
Y428779D03*
Y603779D03*
Y778780D03*
Y953780D03*
Y1128779D03*
Y1303780D03*
Y1478780D03*
Y1653780D03*
Y1828779D03*
Y2003780D03*
G54D20*
X15547Y723112D03*
X25389D03*
X15547Y746734D03*
X25389D03*
X7673Y734923D03*
Y766419D03*
X15547Y793979D03*
X25389D03*
X15547Y825475D03*
X25389D03*
X7673Y853034D03*
X15547Y864845D03*
X25389Y872719D03*
X7673Y884530D03*
X15547Y904215D03*
X25389Y912089D03*
X7673Y923900D03*
X15547Y943585D03*
X25389Y951459D03*
X7673Y963270D03*
X15547Y998703D03*
X7673Y1018388D03*
X25389Y1006577D03*
X15547Y1030199D03*
X25389D03*
X7677Y1069566D03*
X15551Y1089251D03*
X25393Y1073503D03*
Y1112873D03*
X7677Y1108936D03*
X15551Y1128622D03*
Y1167992D03*
X25393Y1152244D03*
X7677Y1148306D03*
X25393Y1191614D03*
X7677Y1187677D03*
X15551Y1207362D03*
X25393Y1230984D03*
X7677Y1227047D03*
X15551Y1246732D03*
X25393Y1262480D03*
Y1270354D03*
Y1286102D03*
X7677Y1266417D03*
Y1282165D03*
Y1313661D03*
X25393Y1317598D03*
X7677Y1360905D03*
X15551Y1356968D03*
X7677Y1376653D03*
X15551Y1364842D03*
X25393Y1372716D03*
X15551Y1388464D03*
X33263Y734923D03*
Y766419D03*
Y853034D03*
Y892404D03*
Y931774D03*
Y971144D03*
Y1018388D03*
X33267Y1093188D03*
Y1132558D03*
Y1171929D03*
Y1211299D03*
Y1250669D03*
Y1360905D03*
Y1384527D03*
G54D32*
X166500Y126110D03*
Y118626D03*
X166329Y140623D03*
X166500Y132705D03*
X166329Y148066D03*
Y156102D03*
Y163621D03*
X156430Y483012D03*
X156259Y490930D03*
X156430Y468933D03*
Y476417D03*
X156259Y513928D03*
Y498373D03*
Y506409D03*
X155444Y822725D03*
X162872D03*
Y830209D03*
X155444D03*
X162872Y836804D03*
X155444D03*
X162701Y844722D03*
X155273D03*
X162701Y852165D03*
X155273D03*
X162701Y860201D03*
X155273D03*
X162701Y867720D03*
X155273D03*
X153124Y1176256D03*
X160552D03*
Y1183740D03*
Y1190335D03*
X153124D03*
Y1183740D03*
X160552Y1169037D03*
X160381Y1198253D03*
X152953D03*
X161537Y1499221D03*
Y1506440D03*
X154109D03*
X153938Y1528437D03*
X154109Y1513924D03*
Y1520519D03*
X161537D03*
Y1513924D03*
X161366Y1528437D03*
X153938Y1535880D03*
Y1543916D03*
Y1551435D03*
X161366Y1535880D03*
Y1543916D03*
Y1551435D03*
X159519Y1866003D03*
X152091Y1880706D03*
Y1887301D03*
X159519D03*
Y1880706D03*
Y1873222D03*
X152091D03*
X151920Y1902662D03*
Y1910698D03*
X159348Y1902662D03*
Y1910698D03*
X151920Y1895219D03*
X159348D03*
X151920Y1918217D03*
X159348D03*
X173928Y126110D03*
Y118626D03*
Y111407D03*
X173757Y140623D03*
X173928Y132705D03*
X173757Y148066D03*
Y156102D03*
Y163621D03*
X175033Y268813D03*
Y282892D03*
X174862Y290810D03*
Y298253D03*
X175033Y276297D03*
X174862Y313808D03*
Y306289D03*
X227714Y237776D03*
Y244995D03*
Y259074D03*
X227543Y266992D03*
Y274435D03*
X227714Y252479D03*
X227543Y289990D03*
Y282471D03*
X232548Y461083D03*
Y482381D03*
X232377Y490299D03*
X232548Y468302D03*
Y475786D03*
X232377Y513297D03*
Y497742D03*
Y505778D03*
X230963Y608108D03*
X238391D03*
X230963Y601513D03*
X238391D03*
Y594029D03*
X230963D03*
X230792Y631505D03*
X238220D03*
X230792Y623469D03*
X238220D03*
X230792Y616026D03*
X238220D03*
X230792Y639024D03*
X238220D03*
X231339Y959673D03*
X238767D03*
Y967157D03*
Y973752D03*
X231339D03*
Y967157D03*
X238767Y952454D03*
X238596Y981670D03*
X231168D03*
X238596Y997149D03*
Y989113D03*
X231168Y997149D03*
Y989113D03*
X238596Y1004668D03*
X231168D03*
X238659Y1215296D03*
X231231D03*
X238659Y1207777D03*
Y1199741D03*
X231231Y1207777D03*
Y1199741D03*
X232559Y1663167D03*
Y1670386D03*
X225131D03*
X232559Y1684465D03*
Y1677870D03*
X232388Y1692383D03*
Y1699826D03*
X225131Y1684465D03*
Y1677870D03*
X224960Y1692383D03*
Y1699826D03*
X232388Y1707862D03*
Y1715381D03*
X224960Y1707862D03*
Y1715381D03*
X279044Y624627D03*
G54D36*
X173385Y32520D03*
Y21890D03*
X183385Y32520D03*
Y21890D03*
X193385Y32520D03*
Y21890D03*
X173385Y196890D03*
X183385D03*
X193385D03*
X173385Y207520D03*
X183385D03*
X193385D03*
X173385Y371890D03*
X183385D03*
X193385D03*
X173385Y382520D03*
X183385D03*
X193385D03*
X173386Y557520D03*
Y546890D03*
X183386Y557520D03*
Y546890D03*
X193386Y557520D03*
Y546890D03*
X173386Y732520D03*
Y721890D03*
X183386Y732520D03*
Y721890D03*
X193386Y732520D03*
Y721890D03*
X173385Y896890D03*
X183385D03*
X193385D03*
X173385Y907520D03*
X183385D03*
X193385D03*
X173385Y1071890D03*
X183385D03*
X193385D03*
X173385Y1082520D03*
X183385D03*
X193385D03*
X173385Y1257520D03*
Y1246890D03*
X183385Y1257520D03*
Y1246890D03*
X193385Y1257520D03*
Y1246890D03*
X173385Y1432520D03*
Y1421890D03*
X183385Y1432520D03*
Y1421890D03*
X193385Y1432520D03*
Y1421890D03*
X173385Y1596890D03*
X183385D03*
X193385D03*
X173385Y1607520D03*
X183385D03*
X193385D03*
X173385Y1771890D03*
X183385D03*
X193385D03*
X173385Y1782520D03*
X183385D03*
X193385D03*
X173385Y1957520D03*
Y1946890D03*
X183385Y1957520D03*
Y1946890D03*
X193385Y1957520D03*
Y1946890D03*
X203385Y32520D03*
Y21890D03*
X213385Y32520D03*
Y21890D03*
X203385Y196890D03*
X213385D03*
X203385Y207520D03*
X213385D03*
X203385Y371890D03*
X213385D03*
X203385Y382520D03*
X213385D03*
X203386Y557520D03*
Y546890D03*
X213386Y557520D03*
Y546890D03*
X203386Y732520D03*
Y721890D03*
X213386Y732520D03*
Y721890D03*
X203385Y896890D03*
X213385D03*
X203385Y907520D03*
X213385D03*
X203385Y1071890D03*
X213385D03*
X203385Y1082520D03*
X213385D03*
X203385Y1257520D03*
Y1246890D03*
X213385Y1257520D03*
Y1246890D03*
X203385Y1432520D03*
Y1421890D03*
X213385Y1432520D03*
Y1421890D03*
X203385Y1596890D03*
X213385D03*
X203385Y1607520D03*
X213385D03*
X203385Y1771890D03*
X213385D03*
X203385Y1782520D03*
X213385D03*
X203385Y1957520D03*
Y1946890D03*
X213385Y1957520D03*
Y1946890D03*
X223385Y32520D03*
Y21890D03*
X233385Y32520D03*
Y21890D03*
X243385Y32520D03*
Y21890D03*
X223385Y196890D03*
X233385D03*
X243385D03*
X223385Y207520D03*
X233385D03*
X243385D03*
X223385Y371890D03*
X233385D03*
X243385D03*
X223385Y382520D03*
X233385D03*
X243385D03*
X223386Y557520D03*
Y546890D03*
X233386Y557520D03*
Y546890D03*
X243386Y557520D03*
Y546890D03*
X223386Y732520D03*
Y721890D03*
X233386Y732520D03*
Y721890D03*
X243386Y732520D03*
Y721890D03*
X223385Y896890D03*
X233385D03*
X243385D03*
X223385Y907520D03*
X233385D03*
X243385D03*
X223385Y1071890D03*
X233385D03*
X243385D03*
X223385Y1082520D03*
X233385D03*
X243385D03*
X223385Y1257520D03*
Y1246890D03*
X233385Y1257520D03*
Y1246890D03*
X243385Y1257520D03*
Y1246890D03*
X223385Y1432520D03*
Y1421890D03*
X233385Y1432520D03*
Y1421890D03*
X243385Y1432520D03*
Y1421890D03*
X223385Y1596890D03*
X233385D03*
X243385D03*
X223385Y1607520D03*
X233385D03*
X243385D03*
X223385Y1771890D03*
X233385D03*
X243385D03*
X223385Y1782520D03*
X233385D03*
X243385D03*
X223385Y1957520D03*
Y1946890D03*
X233385Y1957520D03*
Y1946890D03*
X243385Y1957520D03*
Y1946890D03*
G54D28*
X65354Y114960D03*
Y464960D03*
Y814960D03*
Y1164960D03*
Y1514960D03*
Y1864960D03*
X307086Y127165D03*
Y477165D03*
Y827165D03*
Y1343504D03*
Y1693504D03*
X307087Y2043503D03*
G54D11*
X25219Y18752D03*
X3001Y52034D03*
Y100034D03*
Y150034D03*
Y200034D03*
Y250034D03*
Y300034D03*
Y350034D03*
Y400034D03*
Y450034D03*
Y500034D03*
Y550034D03*
X11677Y578766D03*
X3001Y600034D03*
Y650034D03*
Y700034D03*
Y750034D03*
Y800034D03*
Y850034D03*
Y900034D03*
Y950034D03*
Y1000034D03*
Y1050034D03*
Y1100034D03*
Y1150034D03*
Y1200034D03*
Y1250034D03*
Y1300034D03*
Y1350034D03*
Y1400034D03*
Y1450034D03*
Y1500034D03*
Y1550034D03*
X16484Y1552159D03*
X11085Y1552589D03*
X3006Y1594602D03*
X3012Y1610165D03*
X3001Y1650034D03*
Y1700034D03*
Y1750034D03*
Y1800034D03*
Y1850034D03*
Y1900034D03*
Y1950034D03*
Y2000034D03*
Y2050034D03*
X26833Y2067866D03*
X58750Y579653D03*
X63820Y579654D03*
X61888Y666012D03*
X57458Y1253378D03*
X54543Y1296513D03*
X63061Y1296312D03*
X67568Y1296654D03*
X54108Y1559138D03*
X75219Y18752D03*
X97417Y32853D03*
Y37438D03*
X97536Y376580D03*
X97457Y371909D03*
X97985Y391220D03*
X97643Y396024D03*
X98591Y720745D03*
X98564Y715937D03*
X97443Y739962D03*
X97534Y735248D03*
X98124Y745139D03*
X96904Y1067515D03*
X96948Y1092036D03*
X96949Y1087095D03*
X96774Y1072226D03*
X75475Y1315303D03*
X97403Y1424340D03*
X97825Y1419492D03*
X96993Y1443743D03*
X96996Y1438980D03*
X97465Y1447919D03*
X76833Y2067866D03*
X106335Y22580D03*
X108082Y38899D03*
X102646Y49461D03*
X104116Y82557D03*
X101990Y426104D03*
X101244Y774100D03*
X98652Y1096403D03*
X105684Y1125919D03*
X105455Y1472894D03*
X99103Y1765722D03*
X99068Y1760827D03*
X99047Y1785571D03*
X98873Y1780542D03*
X99294Y1789947D03*
X105669Y1815227D03*
X109991Y2083607D03*
X125219Y3002D03*
X162384Y56744D03*
X161742Y72497D03*
X162586Y68130D03*
X161377Y407575D03*
X161257Y420869D03*
X161826Y756757D03*
X161131Y774878D03*
X161644Y764231D03*
X164539Y1116135D03*
X162140Y1106853D03*
X163099Y1457084D03*
X162524Y1462651D03*
X162242Y1471380D03*
X163250Y1815631D03*
X162140Y1807740D03*
X159991Y2083607D03*
X175219Y3002D03*
X184284Y948331D03*
X184196Y967371D03*
X184632Y983423D03*
X184353Y1001556D03*
X184118Y1019280D03*
X188385Y1020810D03*
X209991Y2083607D03*
X225219Y3002D03*
X267627Y115559D03*
X259991Y2083607D03*
X275219Y3002D03*
X271547Y245353D03*
X276617Y241400D03*
X281193Y241624D03*
X286665Y417844D03*
X291002D03*
X281569Y421169D03*
X274991Y463099D03*
X285348Y595540D03*
X290984Y592215D03*
X273114Y770968D03*
X278184Y767643D03*
X282737D03*
X270070Y812192D03*
X275966Y944767D03*
X281194Y941442D03*
X285874D03*
X282958Y1119471D03*
X288188Y1116146D03*
X283808Y1293959D03*
X289210Y1290634D03*
X270234Y1467760D03*
X275521Y1464435D03*
X279990D03*
X284086Y1644883D03*
X289421Y1641558D03*
X281066Y1819569D03*
X291550Y1814846D03*
X286623Y1814400D03*
X299687Y63778D03*
X304151D03*
X308651D03*
X313089D03*
X294483Y67732D03*
X295509Y592215D03*
X292698Y1116146D03*
X294133Y1290634D03*
X313894Y1513883D03*
X294090Y1641558D03*
X293606Y1858668D03*
X314562Y1994087D03*
X309991Y2083607D03*
X325219Y3002D03*
X322005Y63778D03*
X317567D03*
X325796Y1162266D03*
X324803Y1990272D03*
X320045Y1990215D03*
X359991Y2083607D03*
X375219Y3002D03*
X402512Y17108D03*
Y67108D03*
Y117108D03*
Y167108D03*
Y217108D03*
Y267108D03*
Y317108D03*
Y367108D03*
Y417108D03*
Y467108D03*
Y517108D03*
Y567108D03*
Y617108D03*
Y667108D03*
Y717108D03*
Y767108D03*
Y817108D03*
Y867108D03*
Y917108D03*
Y967108D03*
Y1017108D03*
Y1067108D03*
Y1117108D03*
Y1167108D03*
Y1217108D03*
Y1267108D03*
Y1317108D03*
Y1367108D03*
Y1417108D03*
Y1467108D03*
Y1517108D03*
Y1567108D03*
Y1617108D03*
Y1667108D03*
Y1717108D03*
Y1767108D03*
Y1817108D03*
Y1867108D03*
Y1917108D03*
Y1967108D03*
Y2017108D03*
Y2067108D03*
G54D30*
X119920Y98071D03*
Y108071D03*
Y118071D03*
Y128071D03*
Y138071D03*
Y148071D03*
Y158071D03*
Y168071D03*
Y178071D03*
Y188071D03*
Y198071D03*
Y208071D03*
Y446102D03*
Y456102D03*
Y466102D03*
Y476102D03*
Y486102D03*
Y496102D03*
Y506102D03*
Y516102D03*
Y526102D03*
Y536102D03*
Y546102D03*
Y556102D03*
Y794134D03*
Y804134D03*
Y814134D03*
Y824134D03*
Y834134D03*
Y844134D03*
Y854134D03*
Y864134D03*
Y874134D03*
Y884134D03*
Y894134D03*
Y904134D03*
Y1142165D03*
Y1152165D03*
Y1162165D03*
Y1172165D03*
Y1182165D03*
Y1192165D03*
Y1202165D03*
Y1212165D03*
Y1222165D03*
Y1232165D03*
Y1242165D03*
Y1252165D03*
Y1490197D03*
Y1500197D03*
Y1510197D03*
Y1520197D03*
Y1530197D03*
Y1540197D03*
Y1550197D03*
Y1560197D03*
Y1570197D03*
Y1580197D03*
Y1590197D03*
Y1600197D03*
Y1838228D03*
Y1848228D03*
Y1858228D03*
Y1868228D03*
Y1878228D03*
Y1888228D03*
Y1898228D03*
Y1908228D03*
Y1918228D03*
Y1928228D03*
Y1938228D03*
Y1948228D03*
X139920Y98071D03*
Y128071D03*
Y118071D03*
Y108071D03*
Y148071D03*
Y138071D03*
Y178071D03*
Y168071D03*
Y158071D03*
Y198071D03*
Y188071D03*
Y208071D03*
Y466102D03*
Y456102D03*
Y446102D03*
Y486102D03*
Y476102D03*
Y516102D03*
Y506102D03*
Y496102D03*
Y536102D03*
Y526102D03*
Y556102D03*
Y546102D03*
Y804134D03*
Y794134D03*
Y824134D03*
Y814134D03*
Y854134D03*
Y844134D03*
Y834134D03*
Y874134D03*
Y864134D03*
Y904134D03*
Y894134D03*
Y884134D03*
Y1142165D03*
Y1162165D03*
Y1152165D03*
Y1192165D03*
Y1182165D03*
Y1172165D03*
Y1212165D03*
Y1202165D03*
Y1242165D03*
Y1232165D03*
Y1222165D03*
Y1252165D03*
Y1500197D03*
Y1490197D03*
Y1530197D03*
Y1520197D03*
Y1510197D03*
Y1550197D03*
Y1540197D03*
Y1580197D03*
Y1570197D03*
Y1560197D03*
Y1600197D03*
Y1590197D03*
Y1838228D03*
Y1868228D03*
Y1858228D03*
Y1848228D03*
Y1888228D03*
Y1878228D03*
Y1918228D03*
Y1908228D03*
Y1898228D03*
Y1938228D03*
Y1928228D03*
Y1948228D03*
G54D37*
X189762Y73105D03*
X190289Y152050D03*
X190357Y247568D03*
X190817Y331786D03*
X189761Y421732D03*
X190553Y506517D03*
X192888Y598130D03*
X190816Y681645D03*
X191846Y774526D03*
X191606Y856244D03*
X196311Y947202D03*
X195516Y1032544D03*
X191250Y1122856D03*
X191342Y1206233D03*
X191846Y1299104D03*
X190552Y1380966D03*
X189463Y1474162D03*
X191079Y1557277D03*
X192143Y1648177D03*
X191607Y1731351D03*
X191530Y1823227D03*
X190289Y1900420D03*
X192125Y1998730D03*
X191530Y2043388D03*
G54D23*
X23402Y1685410D03*
Y1701945D03*
Y1735016D03*
Y1751551D03*
Y1784622D03*
Y1801158D03*
G54D24*
X37735Y24953D03*
X32735Y34953D03*
Y243811D03*
G54D15*
X5491Y528544D03*
X67499D03*
%LPC*%
G75*
G54D43*
G01X-723776Y2987387D02*
Y-376795D01*
Y-489221D01*
X1782976D01*
Y-376795D01*
Y2987387D01*
X-723776D01*
G01X-4000Y-62500D02*
Y-137500D01*
X496000D01*
Y-62500D01*
X-4000D01*
G01X8000Y-127500D02*
Y-132500D01*
G01X6543Y-127500D02*
X9457D01*
G01X14367Y-132500D02*
X11833D01*
Y-127500D01*
X14367D01*
G01X13353Y-129917D02*
X11833D01*
G01X16933Y-127500D02*
Y-132500D01*
X19467D01*
G01X23300Y-132667D02*
X23173Y-132583D01*
Y-132417D01*
X23300Y-132333D01*
X23427Y-132417D01*
Y-132583D01*
X23300Y-132667D01*
G01Y-130417D02*
X23173Y-130333D01*
Y-130167D01*
X23300Y-130083D01*
X23427Y-130167D01*
Y-130333D01*
X23300Y-130417D01*
G01X28083Y-134167D02*
X27450Y-133333D01*
X27133Y-132500D01*
Y-129167D01*
X27450Y-128333D01*
X28083Y-127500D01*
G01X33500D02*
X32993Y-127667D01*
X32613Y-128083D01*
X32360Y-128583D01*
X32170Y-129250D01*
X32107Y-130000D01*
X32170Y-130750D01*
X32360Y-131417D01*
X32613Y-131917D01*
X32993Y-132333D01*
X33500Y-132500D01*
X34007Y-132333D01*
X34387Y-131917D01*
X34640Y-131417D01*
X34830Y-130750D01*
X34893Y-130000D01*
X34830Y-129250D01*
X34640Y-128583D01*
X34387Y-128083D01*
X34007Y-127667D01*
X33500Y-127500D01*
G01X37207Y-131500D02*
X37587Y-132083D01*
X38093Y-132417D01*
X38663Y-132500D01*
X39170Y-132417D01*
X39677Y-132000D01*
X39993Y-131500D01*
X40057Y-131000D01*
X39930Y-130417D01*
X39487Y-130000D01*
X39043Y-129833D01*
X38473D01*
G01X39043D02*
X39423Y-129583D01*
X39740Y-129167D01*
X39867Y-128667D01*
X39740Y-128167D01*
X39423Y-127750D01*
X38853Y-127500D01*
X38283Y-127583D01*
X37713Y-127917D01*
G01X44017Y-134167D02*
X44650Y-133333D01*
X44967Y-132500D01*
Y-129167D01*
X44650Y-128333D01*
X44017Y-127500D01*
G01X47407Y-131500D02*
X47787Y-132083D01*
X48293Y-132417D01*
X48863Y-132500D01*
X49370Y-132417D01*
X49877Y-132000D01*
X50193Y-131500D01*
X50257Y-131000D01*
X50130Y-130417D01*
X49687Y-130000D01*
X49243Y-129833D01*
X48673D01*
G01X49243D02*
X49623Y-129583D01*
X49940Y-129167D01*
X50067Y-128667D01*
X49940Y-128167D01*
X49623Y-127750D01*
X49053Y-127500D01*
X48483Y-127583D01*
X47913Y-127917D01*
G01X52697Y-128333D02*
X53077Y-127833D01*
X53520Y-127583D01*
X54027Y-127500D01*
X54660Y-127667D01*
X55103Y-128083D01*
X55230Y-128583D01*
X55167Y-129083D01*
X54913Y-129500D01*
X53647Y-130333D01*
X53077Y-130917D01*
X52697Y-131750D01*
X52570Y-132500D01*
X55230D01*
G01X58873D02*
X59000Y-131417D01*
X59190Y-130500D01*
X59443Y-129667D01*
X59760Y-128750D01*
X60267Y-127500D01*
X57733D01*
G01X63277Y-130833D02*
X64923D01*
G01X67997Y-128333D02*
X68377Y-127833D01*
X68820Y-127583D01*
X69327Y-127500D01*
X69960Y-127667D01*
X70403Y-128083D01*
X70530Y-128583D01*
X70467Y-129083D01*
X70213Y-129500D01*
X68947Y-130333D01*
X68377Y-130917D01*
X67997Y-131750D01*
X67870Y-132500D01*
X70530D01*
G01X72907Y-131500D02*
X73287Y-132083D01*
X73793Y-132417D01*
X74363Y-132500D01*
X74870Y-132417D01*
X75377Y-132000D01*
X75693Y-131500D01*
X75757Y-131000D01*
X75630Y-130417D01*
X75187Y-130000D01*
X74743Y-129833D01*
X74173D01*
G01X74743D02*
X75123Y-129583D01*
X75440Y-129167D01*
X75567Y-128667D01*
X75440Y-128167D01*
X75123Y-127750D01*
X74553Y-127500D01*
X73983Y-127583D01*
X73413Y-127917D01*
G01X80160Y-132500D02*
Y-127500D01*
X77817Y-131083D01*
X80983D01*
G01X83107Y-131750D02*
X83487Y-132167D01*
X83930Y-132417D01*
X84500Y-132500D01*
X85070Y-132333D01*
X85513Y-132000D01*
X85830Y-131417D01*
X85893Y-130750D01*
X85767Y-130083D01*
X85450Y-129667D01*
X85007Y-129333D01*
X84563Y-129250D01*
X84120Y-129333D01*
X83550Y-129667D01*
X83740Y-127500D01*
X85450D01*
G01X93497Y-132500D02*
Y-127500D01*
X95903D01*
G01X95017Y-129917D02*
X93497D01*
G01X98217Y-132500D02*
X99800Y-127500D01*
X101383Y-132500D01*
G01X100813Y-130750D02*
X98787D01*
G01X103570Y-132500D02*
X106230Y-127500D01*
G01X103570D02*
X106230Y-132500D01*
G01X110000Y-132667D02*
X109873Y-132583D01*
Y-132417D01*
X110000Y-132333D01*
X110127Y-132417D01*
Y-132583D01*
X110000Y-132667D01*
G01Y-130417D02*
X109873Y-130333D01*
Y-130167D01*
X110000Y-130083D01*
X110127Y-130167D01*
Y-130333D01*
X110000Y-130417D01*
G01X114783Y-134167D02*
X114150Y-133333D01*
X113833Y-132500D01*
Y-129167D01*
X114150Y-128333D01*
X114783Y-127500D01*
G01X120200D02*
X119693Y-127667D01*
X119313Y-128083D01*
X119060Y-128583D01*
X118870Y-129250D01*
X118807Y-130000D01*
X118870Y-130750D01*
X119060Y-131417D01*
X119313Y-131917D01*
X119693Y-132333D01*
X120200Y-132500D01*
X120707Y-132333D01*
X121087Y-131917D01*
X121340Y-131417D01*
X121530Y-130750D01*
X121593Y-130000D01*
X121530Y-129250D01*
X121340Y-128583D01*
X121087Y-128083D01*
X120707Y-127667D01*
X120200Y-127500D01*
G01X123907Y-131500D02*
X124287Y-132083D01*
X124793Y-132417D01*
X125363Y-132500D01*
X125870Y-132417D01*
X126377Y-132000D01*
X126693Y-131500D01*
X126757Y-131000D01*
X126630Y-130417D01*
X126187Y-130000D01*
X125743Y-129833D01*
X125173D01*
G01X125743D02*
X126123Y-129583D01*
X126440Y-129167D01*
X126567Y-128667D01*
X126440Y-128167D01*
X126123Y-127750D01*
X125553Y-127500D01*
X124983Y-127583D01*
X124413Y-127917D01*
G01X130717Y-134167D02*
X131350Y-133333D01*
X131667Y-132500D01*
Y-129167D01*
X131350Y-128333D01*
X130717Y-127500D01*
G01X134107Y-131500D02*
X134487Y-132083D01*
X134993Y-132417D01*
X135563Y-132500D01*
X136070Y-132417D01*
X136577Y-132000D01*
X136893Y-131500D01*
X136957Y-131000D01*
X136830Y-130417D01*
X136387Y-130000D01*
X135943Y-129833D01*
X135373D01*
G01X135943D02*
X136323Y-129583D01*
X136640Y-129167D01*
X136767Y-128667D01*
X136640Y-128167D01*
X136323Y-127750D01*
X135753Y-127500D01*
X135183Y-127583D01*
X134613Y-127917D01*
G01X139523Y-131917D02*
X139967Y-132333D01*
X140473Y-132500D01*
X140980Y-132333D01*
X141423Y-131833D01*
X141740Y-131083D01*
X141867Y-130333D01*
Y-129417D01*
X141740Y-128667D01*
X141423Y-128000D01*
X141043Y-127667D01*
X140600Y-127500D01*
X140093Y-127667D01*
X139713Y-128000D01*
X139460Y-128500D01*
X139333Y-129167D01*
X139460Y-129750D01*
X139777Y-130333D01*
X140157Y-130667D01*
X140600Y-130750D01*
X141107Y-130583D01*
X141487Y-130167D01*
X141867Y-129417D01*
G01X145573Y-132500D02*
X145700Y-131417D01*
X145890Y-130500D01*
X146143Y-129667D01*
X146460Y-128750D01*
X146967Y-127500D01*
X144433D01*
G01X149977Y-130833D02*
X151623D01*
G01X154507Y-131500D02*
X154887Y-132083D01*
X155393Y-132417D01*
X155963Y-132500D01*
X156470Y-132417D01*
X156977Y-132000D01*
X157293Y-131500D01*
X157357Y-131000D01*
X157230Y-130417D01*
X156787Y-130000D01*
X156343Y-129833D01*
X155773D01*
G01X156343D02*
X156723Y-129583D01*
X157040Y-129167D01*
X157167Y-128667D01*
X157040Y-128167D01*
X156723Y-127750D01*
X156153Y-127500D01*
X155583Y-127583D01*
X155013Y-127917D01*
G01X159797Y-130417D02*
X160240Y-129833D01*
X160620Y-129500D01*
X161127Y-129333D01*
X161570Y-129500D01*
X161887Y-129833D01*
X162140Y-130333D01*
X162203Y-130917D01*
X162140Y-131417D01*
X161887Y-131917D01*
X161507Y-132333D01*
X161063Y-132500D01*
X160557Y-132333D01*
X160113Y-131833D01*
X159860Y-131083D01*
X159797Y-130250D01*
X159923Y-129167D01*
X160113Y-128583D01*
X160430Y-128000D01*
X160873Y-127583D01*
X161317Y-127500D01*
X161760Y-127667D01*
X162077Y-128083D01*
G01X166100Y-132500D02*
Y-127500D01*
X165340Y-128500D01*
G01Y-132500D02*
X166860D01*
G01X171960D02*
Y-127500D01*
X169617Y-131083D01*
X172783D01*
G01X191000Y-62500D02*
Y-137500D01*
G01Y-112500D02*
X294000D01*
Y-87500D01*
G01X191000D02*
X294000D01*
G01X301507Y-122500D02*
Y-117500D01*
X302773D01*
X303280Y-117750D01*
X303660Y-118083D01*
X303977Y-118583D01*
X304230Y-119167D01*
X304293Y-120000D01*
X304230Y-120833D01*
X303977Y-121417D01*
X303660Y-121917D01*
X303280Y-122250D01*
X302773Y-122500D01*
X301507D01*
G01X306417D02*
X308000Y-117500D01*
X309583Y-122500D01*
G01X309013Y-120750D02*
X306987D01*
G01X313100Y-117500D02*
Y-122500D01*
G01X311643Y-117500D02*
X314557D01*
G01X319467Y-122500D02*
X316933D01*
Y-117500D01*
X319467D01*
G01X318453Y-119917D02*
X316933D01*
G01X323300Y-122667D02*
X323173Y-122583D01*
Y-122417D01*
X323300Y-122333D01*
X323427Y-122417D01*
Y-122583D01*
X323300Y-122667D01*
G01Y-120417D02*
X323173Y-120333D01*
Y-120167D01*
X323300Y-120083D01*
X323427Y-120167D01*
Y-120333D01*
X323300Y-120417D01*
G01X296000Y-62500D02*
Y-137500D01*
G01X294000Y-62500D02*
Y-137500D01*
G01X301633Y-97500D02*
Y-92500D01*
X303153D01*
X303660Y-92750D01*
X304040Y-93333D01*
X304167Y-94000D01*
X304040Y-94667D01*
X303723Y-95167D01*
X303153Y-95417D01*
X301633D01*
G01X306860Y-97667D02*
X309140Y-92500D01*
G01X311643Y-97500D02*
Y-92500D01*
X314557Y-97500D01*
Y-92500D01*
G01X318200Y-97667D02*
X318073Y-97583D01*
Y-97417D01*
X318200Y-97333D01*
X318327Y-97417D01*
Y-97583D01*
X318200Y-97667D01*
G01Y-95417D02*
X318073Y-95333D01*
Y-95167D01*
X318200Y-95083D01*
X318327Y-95167D01*
Y-95333D01*
X318200Y-95417D01*
G01X296000Y-112500D02*
X496000D01*
G01X301633Y-72500D02*
Y-67500D01*
X303153D01*
X303660Y-67750D01*
X304040Y-68333D01*
X304167Y-69000D01*
X304040Y-69667D01*
X303723Y-70167D01*
X303153Y-70417D01*
X301633D01*
G01X306733Y-72500D02*
Y-67500D01*
X308317D01*
X308823Y-67750D01*
X309140Y-68083D01*
X309267Y-68750D01*
X309140Y-69417D01*
X308760Y-69833D01*
X308317Y-70083D01*
X306733D01*
G01X308317D02*
X309267Y-72500D01*
G01X313100D02*
X312593Y-72417D01*
X312150Y-72083D01*
X311770Y-71583D01*
X311517Y-71000D01*
X311390Y-70333D01*
Y-69667D01*
X311517Y-69000D01*
X311770Y-68417D01*
X312150Y-67917D01*
X312593Y-67583D01*
X313100Y-67500D01*
X313607Y-67583D01*
X314050Y-67917D01*
X314430Y-68417D01*
X314683Y-69000D01*
X314810Y-69667D01*
Y-70333D01*
X314683Y-71000D01*
X314430Y-71583D01*
X314050Y-72083D01*
X313607Y-72417D01*
X313100Y-72500D01*
G01X316933Y-71500D02*
X317250Y-72000D01*
X317630Y-72333D01*
X318073Y-72500D01*
X318580Y-72333D01*
X318960Y-72000D01*
X319340Y-71500D01*
X319467Y-70833D01*
Y-67500D01*
G01X324567Y-72500D02*
X322033D01*
Y-67500D01*
X324567D01*
G01X323553Y-69917D02*
X322033D01*
G01X329793Y-67917D02*
X329413Y-67667D01*
X328970Y-67500D01*
X328463D01*
X327893Y-67750D01*
X327450Y-68167D01*
X327133Y-68667D01*
X326880Y-69500D01*
X326817Y-70250D01*
X326943Y-71000D01*
X327133Y-71500D01*
X327513Y-72000D01*
X327957Y-72333D01*
X328400Y-72500D01*
X328843D01*
X329287Y-72333D01*
X329667Y-72083D01*
X329983Y-71750D01*
G01X333500Y-67500D02*
Y-72500D01*
G01X332043Y-67500D02*
X334957D01*
G01X338600Y-72667D02*
X338473Y-72583D01*
Y-72417D01*
X338600Y-72333D01*
X338727Y-72417D01*
Y-72583D01*
X338600Y-72667D01*
G01Y-70417D02*
X338473Y-70333D01*
Y-70167D01*
X338600Y-70083D01*
X338727Y-70167D01*
Y-70333D01*
X338600Y-70417D01*
G01X296000Y-87500D02*
X496000D01*
G01X411000Y-112500D02*
Y-137500D01*
G01X416633Y-122500D02*
Y-117500D01*
X418217D01*
X418723Y-117750D01*
X419040Y-118083D01*
X419167Y-118750D01*
X419040Y-119417D01*
X418660Y-119833D01*
X418217Y-120083D01*
X416633D01*
G01X418217D02*
X419167Y-122500D01*
G01X424267D02*
X421733D01*
Y-117500D01*
X424267D01*
G01X423253Y-119917D02*
X421733D01*
G01X426517Y-117500D02*
X428100Y-122500D01*
X429683Y-117500D01*
G01X433200Y-122667D02*
X433073Y-122583D01*
Y-122417D01*
X433200Y-122333D01*
X433327Y-122417D01*
Y-122583D01*
X433200Y-122667D01*
G01Y-120417D02*
X433073Y-120333D01*
Y-120167D01*
X433200Y-120083D01*
X433327Y-120167D01*
Y-120333D01*
X433200Y-120417D01*
G01X460000Y-112500D02*
Y-137500D01*
G01X-723776Y2987387D02*
Y-376795D01*
Y-489221D01*
X1782976D01*
Y-376795D01*
Y2987387D01*
X-723776D01*
G01X6705Y-124160D02*
X7332Y-124685D01*
X8037Y-125000D01*
X8663D01*
X9290Y-124685D01*
X9760Y-124160D01*
X9995Y-123425D01*
X9838Y-122690D01*
X9447Y-122060D01*
X8742Y-121640D01*
X7802Y-121430D01*
X7253Y-121010D01*
X7018Y-120275D01*
X7175Y-119540D01*
X7567Y-119015D01*
X8115Y-118700D01*
X8663D01*
X9212Y-118910D01*
X9682Y-119435D01*
G01X13005Y-125000D02*
Y-118700D01*
G01X16295D02*
Y-125000D01*
G01Y-121850D02*
X13005D01*
G01X20010Y-118700D02*
X21890D01*
G01X20950D02*
Y-125000D01*
G01X20010D02*
X21890D01*
G01X28817D02*
X25683D01*
Y-118700D01*
X28817D01*
G01X27563Y-121745D02*
X25683D01*
G01X31748Y-125000D02*
Y-118700D01*
X35352Y-125000D01*
Y-118700D01*
G01X39693Y-126155D02*
X40007Y-124790D01*
G01X46150Y-118700D02*
Y-125000D01*
G01X44348Y-118700D02*
X47952D01*
G01X50492Y-125000D02*
X52450Y-118700D01*
X54408Y-125000D01*
G01X53703Y-122795D02*
X51197D01*
G01X57810Y-118700D02*
X59690D01*
G01X58750D02*
Y-125000D01*
G01X57810D02*
X59690D01*
G01X62700Y-118700D02*
X63797Y-125000D01*
X65050Y-118700D01*
X66303Y-125000D01*
X67400Y-118700D01*
G01X69392Y-125000D02*
X71350Y-118700D01*
X73308Y-125000D01*
G01X72603Y-122795D02*
X70097D01*
G01X75848Y-125000D02*
Y-118700D01*
X79452Y-125000D01*
Y-118700D01*
G01X88683Y-125000D02*
Y-118700D01*
X90642D01*
X91268Y-119015D01*
X91660Y-119435D01*
X91817Y-120275D01*
X91660Y-121115D01*
X91190Y-121640D01*
X90642Y-121955D01*
X88683D01*
G01X90642D02*
X91817Y-125000D01*
G01X96550Y-125210D02*
X96393Y-125105D01*
Y-124895D01*
X96550Y-124790D01*
X96707Y-124895D01*
Y-125105D01*
X96550Y-125210D01*
G01X102850Y-125000D02*
X102223Y-124895D01*
X101675Y-124475D01*
X101205Y-123845D01*
X100892Y-123110D01*
X100735Y-122270D01*
Y-121430D01*
X100892Y-120590D01*
X101205Y-119855D01*
X101675Y-119225D01*
X102223Y-118805D01*
X102850Y-118700D01*
X103477Y-118805D01*
X104025Y-119225D01*
X104495Y-119855D01*
X104808Y-120590D01*
X104965Y-121430D01*
Y-122270D01*
X104808Y-123110D01*
X104495Y-123845D01*
X104025Y-124475D01*
X103477Y-124895D01*
X102850Y-125000D01*
G01X109150Y-125210D02*
X108993Y-125105D01*
Y-124895D01*
X109150Y-124790D01*
X109307Y-124895D01*
Y-125105D01*
X109150Y-125210D01*
G01X117173Y-119225D02*
X116703Y-118910D01*
X116155Y-118700D01*
X115528D01*
X114823Y-119015D01*
X114275Y-119540D01*
X113883Y-120170D01*
X113570Y-121220D01*
X113492Y-122165D01*
X113648Y-123110D01*
X113883Y-123740D01*
X114353Y-124370D01*
X114902Y-124790D01*
X115450Y-125000D01*
X115998D01*
X116547Y-124790D01*
X117017Y-124475D01*
X117408Y-124055D01*
G01X121750Y-125210D02*
X121593Y-125105D01*
Y-124895D01*
X121750Y-124790D01*
X121907Y-124895D01*
Y-125105D01*
X121750Y-125210D01*
G01X6627Y-115000D02*
Y-108700D01*
G01X9603D02*
X6627Y-112585D01*
G01X10073Y-115000D02*
X7958Y-110800D01*
G01X12927Y-108700D02*
Y-113215D01*
X13240Y-114160D01*
X13867Y-114790D01*
X14650Y-115000D01*
X15433Y-114790D01*
X16060Y-114160D01*
X16373Y-113215D01*
Y-108700D01*
G01X22517Y-115000D02*
X19383D01*
Y-108700D01*
X22517D01*
G01X21263Y-111745D02*
X19383D01*
G01X26310Y-108700D02*
X28190D01*
G01X27250D02*
Y-115000D01*
G01X26310D02*
X28190D01*
G01X38205Y-114160D02*
X38832Y-114685D01*
X39537Y-115000D01*
X40163D01*
X40790Y-114685D01*
X41260Y-114160D01*
X41495Y-113425D01*
X41338Y-112690D01*
X40947Y-112060D01*
X40242Y-111640D01*
X39302Y-111430D01*
X38753Y-111010D01*
X38518Y-110275D01*
X38675Y-109540D01*
X39067Y-109015D01*
X39615Y-108700D01*
X40163D01*
X40712Y-108910D01*
X41182Y-109435D01*
G01X44505Y-115000D02*
Y-108700D01*
G01X47795D02*
Y-115000D01*
G01Y-111850D02*
X44505D01*
G01X50492Y-115000D02*
X52450Y-108700D01*
X54408Y-115000D01*
G01X53703Y-112795D02*
X51197D01*
G01X56948Y-115000D02*
Y-108700D01*
X60552Y-115000D01*
Y-108700D01*
G01X69705Y-115000D02*
Y-108700D01*
G01X72995D02*
Y-115000D01*
G01Y-111850D02*
X69705D01*
G01X76005Y-114160D02*
X76632Y-114685D01*
X77337Y-115000D01*
X77963D01*
X78590Y-114685D01*
X79060Y-114160D01*
X79295Y-113425D01*
X79138Y-112690D01*
X78747Y-112060D01*
X78042Y-111640D01*
X77102Y-111430D01*
X76553Y-111010D01*
X76318Y-110275D01*
X76475Y-109540D01*
X76867Y-109015D01*
X77415Y-108700D01*
X77963D01*
X78512Y-108910D01*
X78982Y-109435D01*
G01X83010Y-108700D02*
X84890D01*
G01X83950D02*
Y-115000D01*
G01X83010D02*
X84890D01*
G01X88292D02*
X90250Y-108700D01*
X92208Y-115000D01*
G01X91503Y-112795D02*
X88997D01*
G01X94748Y-115000D02*
Y-108700D01*
X98352Y-115000D01*
Y-108700D01*
G01X103320Y-111850D02*
X104887D01*
Y-113740D01*
X104417Y-114370D01*
X103868Y-114790D01*
X103085Y-115000D01*
X102302Y-114790D01*
X101753Y-114370D01*
X101283Y-113740D01*
X100970Y-113005D01*
X100813Y-112165D01*
Y-111430D01*
X100970Y-110800D01*
X101283Y-110065D01*
X101753Y-109435D01*
X102223Y-109015D01*
X102850Y-108700D01*
X103398D01*
X104025Y-108910D01*
X104495Y-109330D01*
G01X108993Y-116155D02*
X109307Y-114790D01*
G01X115450Y-108700D02*
Y-115000D01*
G01X113648Y-108700D02*
X117252D01*
G01X119792Y-115000D02*
X121750Y-108700D01*
X123708Y-115000D01*
G01X123003Y-112795D02*
X120497D01*
G01X128050Y-115000D02*
X127423Y-114895D01*
X126875Y-114475D01*
X126405Y-113845D01*
X126092Y-113110D01*
X125935Y-112270D01*
Y-111430D01*
X126092Y-110590D01*
X126405Y-109855D01*
X126875Y-109225D01*
X127423Y-108805D01*
X128050Y-108700D01*
X128677Y-108805D01*
X129225Y-109225D01*
X129695Y-109855D01*
X130008Y-110590D01*
X130165Y-111430D01*
Y-112270D01*
X130008Y-113110D01*
X129695Y-113845D01*
X129225Y-114475D01*
X128677Y-114895D01*
X128050Y-115000D01*
G01X140650D02*
Y-112165D01*
X139083Y-108700D01*
G01X142217D02*
X140650Y-112165D01*
G01X145227Y-108700D02*
Y-113215D01*
X145540Y-114160D01*
X146167Y-114790D01*
X146950Y-115000D01*
X147733Y-114790D01*
X148360Y-114160D01*
X148673Y-113215D01*
Y-108700D01*
G01X151292Y-115000D02*
X153250Y-108700D01*
X155208Y-115000D01*
G01X154503Y-112795D02*
X151997D01*
G01X157748Y-115000D02*
Y-108700D01*
X161352Y-115000D01*
Y-108700D01*
G01X30650Y-92300D02*
X28130Y-91883D01*
X25925Y-90217D01*
X24035Y-87717D01*
X22775Y-84800D01*
X22145Y-81467D01*
Y-78133D01*
X22775Y-74800D01*
X24035Y-71883D01*
X25925Y-69384D01*
X28130Y-67717D01*
X30650Y-67300D01*
X33170Y-67717D01*
X35375Y-69384D01*
X37265Y-71883D01*
X38525Y-74800D01*
X39155Y-78133D01*
Y-81467D01*
X38525Y-84800D01*
X37265Y-87717D01*
X35375Y-90217D01*
X33170Y-91883D01*
X30650Y-92300D01*
G01X33170Y-85633D02*
X36950Y-92300D01*
G01X50495Y-75634D02*
Y-87300D01*
X51755Y-90217D01*
X53645Y-91883D01*
X55850Y-92300D01*
X58055Y-91883D01*
X59945Y-90217D01*
X61205Y-87300D01*
G01Y-92300D02*
Y-75634D01*
G01X86720Y-92300D02*
Y-75634D01*
G01Y-78550D02*
X85460Y-76884D01*
X83570Y-76050D01*
X81365Y-75634D01*
X79160Y-76467D01*
X77270Y-78133D01*
X76010Y-80634D01*
X75380Y-83967D01*
X76010Y-87300D01*
X77270Y-89801D01*
X79160Y-91467D01*
X81365Y-92300D01*
X83570Y-91883D01*
X85460Y-90634D01*
X86720Y-88967D01*
G01X100895Y-92300D02*
Y-75634D01*
G01Y-79800D02*
X102155Y-77717D01*
X104045Y-76050D01*
X106565Y-75634D01*
X108770Y-76050D01*
X110660Y-77717D01*
X111605Y-80634D01*
Y-92300D01*
G01X131450Y-67300D02*
Y-92300D01*
G01X127040Y-75634D02*
X135860D01*
G01X162320Y-92300D02*
Y-75634D01*
G01Y-78550D02*
X161060Y-76884D01*
X159170Y-76050D01*
X156965Y-75634D01*
X154760Y-76467D01*
X152870Y-78133D01*
X151610Y-80634D01*
X150980Y-83967D01*
X151610Y-87300D01*
X152870Y-89801D01*
X154760Y-91467D01*
X156965Y-92300D01*
X159170Y-91883D01*
X161060Y-90634D01*
X162320Y-88967D01*
G01X6548Y-105000D02*
Y-98700D01*
X10152Y-105000D01*
Y-98700D01*
G01X14650Y-105000D02*
X14023Y-104895D01*
X13475Y-104475D01*
X13005Y-103845D01*
X12692Y-103110D01*
X12535Y-102270D01*
Y-101430D01*
X12692Y-100590D01*
X13005Y-99855D01*
X13475Y-99225D01*
X14023Y-98805D01*
X14650Y-98700D01*
X15277Y-98805D01*
X15825Y-99225D01*
X16295Y-99855D01*
X16608Y-100590D01*
X16765Y-101430D01*
Y-102270D01*
X16608Y-103110D01*
X16295Y-103845D01*
X15825Y-104475D01*
X15277Y-104895D01*
X14650Y-105000D01*
G01X20950Y-105210D02*
X20793Y-105105D01*
Y-104895D01*
X20950Y-104790D01*
X21107Y-104895D01*
Y-105105D01*
X20950Y-105210D01*
G01X27250Y-105000D02*
Y-98700D01*
X26310Y-99960D01*
G01Y-105000D02*
X28190D01*
G01X33550D02*
X34098Y-104895D01*
X34725Y-104580D01*
X35117Y-104055D01*
X35273Y-103320D01*
X35117Y-102585D01*
X34647Y-101955D01*
X33942Y-101640D01*
X33158D01*
X32688Y-101430D01*
X32297Y-100905D01*
X32140Y-100170D01*
X32375Y-99435D01*
X32923Y-98910D01*
X33550Y-98700D01*
X34177Y-98910D01*
X34725Y-99435D01*
X34960Y-100170D01*
X34803Y-100905D01*
X34412Y-101430D01*
X33942Y-101640D01*
X33158D01*
X32453Y-101955D01*
X31983Y-102585D01*
X31827Y-103320D01*
X31983Y-104055D01*
X32375Y-104580D01*
X33002Y-104895D01*
X33550Y-105000D01*
G01X39850D02*
X40398Y-104895D01*
X41025Y-104580D01*
X41417Y-104055D01*
X41573Y-103320D01*
X41417Y-102585D01*
X40947Y-101955D01*
X40242Y-101640D01*
X39458D01*
X38988Y-101430D01*
X38597Y-100905D01*
X38440Y-100170D01*
X38675Y-99435D01*
X39223Y-98910D01*
X39850Y-98700D01*
X40477Y-98910D01*
X41025Y-99435D01*
X41260Y-100170D01*
X41103Y-100905D01*
X40712Y-101430D01*
X40242Y-101640D01*
X39458D01*
X38753Y-101955D01*
X38283Y-102585D01*
X38127Y-103320D01*
X38283Y-104055D01*
X38675Y-104580D01*
X39302Y-104895D01*
X39850Y-105000D01*
G01X45993Y-106155D02*
X46307Y-104790D01*
G01X50100Y-98700D02*
X51197Y-105000D01*
X52450Y-98700D01*
X53703Y-105000D01*
X54800Y-98700D01*
G01X60317Y-105000D02*
X57183D01*
Y-98700D01*
X60317D01*
G01X59063Y-101745D02*
X57183D01*
G01X63248Y-105000D02*
Y-98700D01*
X66852Y-105000D01*
Y-98700D01*
G01X76005Y-105000D02*
Y-98700D01*
G01X79295D02*
Y-105000D01*
G01Y-101850D02*
X76005D01*
G01X81600Y-98700D02*
X82697Y-105000D01*
X83950Y-98700D01*
X85203Y-105000D01*
X86300Y-98700D01*
G01X88292Y-105000D02*
X90250Y-98700D01*
X92208Y-105000D01*
G01X91503Y-102795D02*
X88997D01*
G01X101362Y-99750D02*
X101832Y-99120D01*
X102380Y-98805D01*
X103007Y-98700D01*
X103790Y-98910D01*
X104338Y-99435D01*
X104495Y-100065D01*
X104417Y-100695D01*
X104103Y-101220D01*
X102537Y-102270D01*
X101832Y-103005D01*
X101362Y-104055D01*
X101205Y-105000D01*
X104495D01*
G01X107348D02*
Y-98700D01*
X110952Y-105000D01*
Y-98700D01*
G01X113727Y-105000D02*
Y-98700D01*
X115293D01*
X115920Y-99015D01*
X116390Y-99435D01*
X116782Y-100065D01*
X117095Y-100800D01*
X117173Y-101850D01*
X117095Y-102900D01*
X116782Y-103635D01*
X116390Y-104265D01*
X115920Y-104685D01*
X115293Y-105000D01*
X113727D01*
G01X126483D02*
Y-98700D01*
X128442D01*
X129068Y-99015D01*
X129460Y-99435D01*
X129617Y-100275D01*
X129460Y-101115D01*
X128990Y-101640D01*
X128442Y-101955D01*
X126483D01*
G01X128442D02*
X129617Y-105000D01*
G01X132627D02*
Y-98700D01*
X134193D01*
X134820Y-99015D01*
X135290Y-99435D01*
X135682Y-100065D01*
X135995Y-100800D01*
X136073Y-101850D01*
X135995Y-102900D01*
X135682Y-103635D01*
X135290Y-104265D01*
X134820Y-104685D01*
X134193Y-105000D01*
X132627D01*
G01X140650Y-105210D02*
X140493Y-105105D01*
Y-104895D01*
X140650Y-104790D01*
X140807Y-104895D01*
Y-105105D01*
X140650Y-105210D01*
G01X202000Y-72000D02*
Y-80000D01*
X206000D01*
G01X213800D02*
Y-74667D01*
G01Y-75600D02*
X213400Y-75067D01*
X212800Y-74800D01*
X212100Y-74667D01*
X211400Y-74933D01*
X210800Y-75467D01*
X210400Y-76267D01*
X210200Y-77333D01*
X210400Y-78400D01*
X210800Y-79200D01*
X211400Y-79733D01*
X212100Y-80000D01*
X212800Y-79867D01*
X213400Y-79467D01*
X213800Y-78934D01*
G01X217900Y-82400D02*
X218500Y-82667D01*
X219300Y-82400D01*
X219800Y-81867D01*
X220200Y-81200D01*
X220800Y-79067D01*
X222100Y-74667D01*
G01X218900D02*
X220800Y-79067D01*
G01X226500Y-76400D02*
X229700D01*
X229400Y-75467D01*
X228900Y-74933D01*
X228200Y-74667D01*
X227500Y-74800D01*
X226900Y-75200D01*
X226500Y-76133D01*
X226300Y-76934D01*
Y-77733D01*
X226500Y-78533D01*
X227000Y-79333D01*
X227600Y-79867D01*
X228300Y-80000D01*
X229000Y-79733D01*
X229700Y-78934D01*
G01X234600Y-80000D02*
Y-74667D01*
G01Y-75733D02*
X235100Y-75200D01*
X235600Y-74800D01*
X236300Y-74667D01*
X236800Y-74800D01*
X237400Y-75200D01*
G01X223400Y-128934D02*
X224200Y-129600D01*
X225100Y-130000D01*
X225900D01*
X226700Y-129600D01*
X227300Y-128934D01*
X227600Y-128000D01*
X227400Y-127067D01*
X226900Y-126267D01*
X226000Y-125733D01*
X224800Y-125467D01*
X224100Y-124933D01*
X223800Y-124000D01*
X224000Y-123067D01*
X224500Y-122400D01*
X225200Y-122000D01*
X225900D01*
X226600Y-122267D01*
X227200Y-122933D01*
G01X235300Y-130000D02*
Y-124667D01*
G01Y-125600D02*
X234900Y-125067D01*
X234300Y-124800D01*
X233600Y-124667D01*
X232900Y-124933D01*
X232300Y-125467D01*
X231900Y-126267D01*
X231700Y-127333D01*
X231900Y-128400D01*
X232300Y-129200D01*
X232900Y-129733D01*
X233600Y-130000D01*
X234300Y-129867D01*
X234900Y-129467D01*
X235300Y-128934D01*
G01X239800Y-130000D02*
Y-124667D01*
G01Y-126000D02*
X240200Y-125333D01*
X240800Y-124800D01*
X241600Y-124667D01*
X242300Y-124800D01*
X242900Y-125333D01*
X243200Y-126267D01*
Y-130000D01*
G01X251300Y-122000D02*
Y-130000D01*
G01Y-128800D02*
X250900Y-129467D01*
X250300Y-129867D01*
X249600Y-130000D01*
X248800Y-129733D01*
X248200Y-129067D01*
X247800Y-128267D01*
X247700Y-127333D01*
X247800Y-126400D01*
X248200Y-125600D01*
X248800Y-124933D01*
X249600Y-124667D01*
X250300Y-124800D01*
X250800Y-125067D01*
X251300Y-125600D01*
G01X255400Y-132400D02*
X256000Y-132667D01*
X256800Y-132400D01*
X257300Y-131867D01*
X257700Y-131200D01*
X258300Y-129067D01*
X259600Y-124667D01*
G01X256400D02*
X258300Y-129067D01*
G01X231100Y-101000D02*
X233100D01*
Y-103400D01*
X232500Y-104200D01*
X231800Y-104733D01*
X230800Y-105000D01*
X229800Y-104733D01*
X229100Y-104200D01*
X228500Y-103400D01*
X228100Y-102467D01*
X227900Y-101400D01*
Y-100467D01*
X228100Y-99667D01*
X228500Y-98733D01*
X229100Y-97933D01*
X229700Y-97400D01*
X230500Y-97000D01*
X231200D01*
X232000Y-97267D01*
X232600Y-97800D01*
G01X236200Y-105000D02*
Y-97000D01*
X240800Y-105000D01*
Y-97000D01*
G01X244300Y-105000D02*
Y-97000D01*
X246300D01*
X247100Y-97400D01*
X247700Y-97933D01*
X248200Y-98733D01*
X248600Y-99667D01*
X248700Y-101000D01*
X248600Y-102333D01*
X248200Y-103267D01*
X247700Y-104067D01*
X247100Y-104600D01*
X246300Y-105000D01*
X244300D01*
G01X253600Y-73333D02*
X254200Y-72533D01*
X254900Y-72133D01*
X255700Y-72000D01*
X256700Y-72267D01*
X257400Y-72933D01*
X257600Y-73733D01*
X257500Y-74534D01*
X257100Y-75200D01*
X255100Y-76533D01*
X254200Y-77467D01*
X253600Y-78800D01*
X253400Y-80000D01*
X257600D01*
G01X328600Y-123333D02*
X329200Y-122533D01*
X329900Y-122133D01*
X330700Y-122000D01*
X331700Y-122267D01*
X332400Y-122933D01*
X332600Y-123733D01*
X332500Y-124534D01*
X332100Y-125200D01*
X330100Y-126533D01*
X329200Y-127467D01*
X328600Y-128800D01*
X328400Y-130000D01*
X332600D01*
G01X338500Y-122000D02*
X337700Y-122267D01*
X337100Y-122933D01*
X336700Y-123733D01*
X336400Y-124800D01*
X336300Y-126000D01*
X336400Y-127200D01*
X336700Y-128267D01*
X337100Y-129067D01*
X337700Y-129733D01*
X338500Y-130000D01*
X339300Y-129733D01*
X339900Y-129067D01*
X340300Y-128267D01*
X340600Y-127200D01*
X340700Y-126000D01*
X340600Y-124800D01*
X340300Y-123733D01*
X339900Y-122933D01*
X339300Y-122267D01*
X338500Y-122000D01*
G01X346500Y-130000D02*
Y-122000D01*
X345300Y-123600D01*
G01Y-130000D02*
X347700D01*
G01X352600Y-123333D02*
X353200Y-122533D01*
X353900Y-122133D01*
X354700Y-122000D01*
X355700Y-122267D01*
X356400Y-122933D01*
X356600Y-123733D01*
X356500Y-124534D01*
X356100Y-125200D01*
X354100Y-126533D01*
X353200Y-127467D01*
X352600Y-128800D01*
X352400Y-130000D01*
X356600D01*
G01X360700Y-130267D02*
X364300Y-122000D01*
G01X370500D02*
X369700Y-122267D01*
X369100Y-122933D01*
X368700Y-123733D01*
X368400Y-124800D01*
X368300Y-126000D01*
X368400Y-127200D01*
X368700Y-128267D01*
X369100Y-129067D01*
X369700Y-129733D01*
X370500Y-130000D01*
X371300Y-129733D01*
X371900Y-129067D01*
X372300Y-128267D01*
X372600Y-127200D01*
X372700Y-126000D01*
X372600Y-124800D01*
X372300Y-123733D01*
X371900Y-122933D01*
X371300Y-122267D01*
X370500Y-122000D01*
G01X376800Y-129067D02*
X377500Y-129733D01*
X378300Y-130000D01*
X379100Y-129733D01*
X379800Y-128934D01*
X380300Y-127733D01*
X380500Y-126533D01*
Y-125067D01*
X380300Y-123867D01*
X379800Y-122800D01*
X379200Y-122267D01*
X378500Y-122000D01*
X377700Y-122267D01*
X377100Y-122800D01*
X376700Y-123600D01*
X376500Y-124667D01*
X376700Y-125600D01*
X377200Y-126533D01*
X377800Y-127067D01*
X378500Y-127200D01*
X379300Y-126934D01*
X379900Y-126267D01*
X380500Y-125067D01*
G01X384700Y-130267D02*
X388300Y-122000D01*
G01X392600Y-123333D02*
X393200Y-122533D01*
X393900Y-122133D01*
X394700Y-122000D01*
X395700Y-122267D01*
X396400Y-122933D01*
X396600Y-123733D01*
X396500Y-124534D01*
X396100Y-125200D01*
X394100Y-126533D01*
X393200Y-127467D01*
X392600Y-128800D01*
X392400Y-130000D01*
X396600D01*
G01X402500D02*
X403200Y-129867D01*
X404000Y-129467D01*
X404500Y-128800D01*
X404700Y-127867D01*
X404500Y-126934D01*
X403900Y-126133D01*
X403000Y-125733D01*
X402000D01*
X401400Y-125467D01*
X400900Y-124800D01*
X400700Y-123867D01*
X401000Y-122933D01*
X401700Y-122267D01*
X402500Y-122000D01*
X403300Y-122267D01*
X404000Y-122933D01*
X404300Y-123867D01*
X404100Y-124800D01*
X403600Y-125467D01*
X403000Y-125733D01*
X402000D01*
X401100Y-126133D01*
X400500Y-126934D01*
X400300Y-127867D01*
X400500Y-128800D01*
X401000Y-129467D01*
X401800Y-129867D01*
X402500Y-130000D01*
G01X328300Y-105000D02*
Y-97000D01*
X330300D01*
X331100Y-97400D01*
X331700Y-97933D01*
X332200Y-98733D01*
X332600Y-99667D01*
X332700Y-101000D01*
X332600Y-102333D01*
X332200Y-103267D01*
X331700Y-104067D01*
X331100Y-104600D01*
X330300Y-105000D01*
X328300D01*
G01X336000D02*
X338500Y-97000D01*
X341000Y-105000D01*
G01X340100Y-102200D02*
X336900D01*
G01X346500Y-97000D02*
X345700Y-97267D01*
X345100Y-97933D01*
X344700Y-98733D01*
X344400Y-99800D01*
X344300Y-101000D01*
X344400Y-102200D01*
X344700Y-103267D01*
X345100Y-104067D01*
X345700Y-104733D01*
X346500Y-105000D01*
X347300Y-104733D01*
X347900Y-104067D01*
X348300Y-103267D01*
X348600Y-102200D01*
X348700Y-101000D01*
X348600Y-99800D01*
X348300Y-98733D01*
X347900Y-97933D01*
X347300Y-97267D01*
X346500Y-97000D01*
G01X354500D02*
Y-105000D01*
G01X352200Y-97000D02*
X356800D01*
G01X360600Y-101667D02*
X361300Y-100733D01*
X361900Y-100200D01*
X362700Y-99933D01*
X363400Y-100200D01*
X363900Y-100733D01*
X364300Y-101533D01*
X364400Y-102467D01*
X364300Y-103267D01*
X363900Y-104067D01*
X363300Y-104733D01*
X362600Y-105000D01*
X361800Y-104733D01*
X361100Y-103934D01*
X360700Y-102733D01*
X360600Y-101400D01*
X360800Y-99667D01*
X361100Y-98733D01*
X361600Y-97800D01*
X362300Y-97133D01*
X363000Y-97000D01*
X363700Y-97267D01*
X364200Y-97933D01*
G01X367900Y-105000D02*
Y-97000D01*
X370500Y-103667D01*
X373100Y-97000D01*
Y-105000D01*
G01X378500Y-97000D02*
Y-105000D01*
G01X376200Y-97000D02*
X380800D01*
G01X387300Y-100733D02*
X387700Y-100333D01*
X388000Y-99667D01*
X388200Y-98733D01*
X388000Y-97933D01*
X387600Y-97400D01*
X386900Y-97000D01*
X384200D01*
Y-105000D01*
X387500D01*
X388200Y-104467D01*
X388600Y-103667D01*
X388800Y-102733D01*
X388600Y-101800D01*
X388000Y-101000D01*
X387300Y-100733D01*
X384200D01*
G01X394500Y-105000D02*
X395200Y-104867D01*
X396000Y-104467D01*
X396500Y-103800D01*
X396700Y-102867D01*
X396500Y-101934D01*
X395900Y-101133D01*
X395000Y-100733D01*
X394000D01*
X393400Y-100467D01*
X392900Y-99800D01*
X392700Y-98867D01*
X393000Y-97933D01*
X393700Y-97267D01*
X394500Y-97000D01*
X395300Y-97267D01*
X396000Y-97933D01*
X396300Y-98867D01*
X396100Y-99800D01*
X395600Y-100467D01*
X395000Y-100733D01*
X394000D01*
X393100Y-101133D01*
X392500Y-101934D01*
X392300Y-102867D01*
X392500Y-103800D01*
X393000Y-104467D01*
X393800Y-104867D01*
X394500Y-105000D01*
G01X400300D02*
Y-97000D01*
X402300D01*
X403100Y-97400D01*
X403700Y-97933D01*
X404200Y-98733D01*
X404600Y-99667D01*
X404700Y-101000D01*
X404600Y-102333D01*
X404200Y-103267D01*
X403700Y-104067D01*
X403100Y-104600D01*
X402300Y-105000D01*
X400300D01*
G01X410500Y-97000D02*
X409700Y-97267D01*
X409100Y-97933D01*
X408700Y-98733D01*
X408400Y-99800D01*
X408300Y-101000D01*
X408400Y-102200D01*
X408700Y-103267D01*
X409100Y-104067D01*
X409700Y-104733D01*
X410500Y-105000D01*
X411300Y-104733D01*
X411900Y-104067D01*
X412300Y-103267D01*
X412600Y-102200D01*
X412700Y-101000D01*
X412600Y-99800D01*
X412300Y-98733D01*
X411900Y-97933D01*
X411300Y-97267D01*
X410500Y-97000D01*
G01X350500Y-72000D02*
Y-80000D01*
G01X348200Y-72000D02*
X352800D01*
G01X356600Y-76667D02*
X357300Y-75733D01*
X357900Y-75200D01*
X358700Y-74933D01*
X359400Y-75200D01*
X359900Y-75733D01*
X360300Y-76533D01*
X360400Y-77467D01*
X360300Y-78267D01*
X359900Y-79067D01*
X359300Y-79733D01*
X358600Y-80000D01*
X357800Y-79733D01*
X357100Y-78934D01*
X356700Y-77733D01*
X356600Y-76400D01*
X356800Y-74667D01*
X357100Y-73733D01*
X357600Y-72800D01*
X358300Y-72133D01*
X359000Y-72000D01*
X359700Y-72267D01*
X360200Y-72933D01*
G01X363900Y-80000D02*
Y-72000D01*
X366500Y-78667D01*
X369100Y-72000D01*
Y-80000D01*
G01X371500Y-82667D02*
X377500D01*
G01X380500Y-80000D02*
Y-72000D01*
X382900D01*
X383700Y-72400D01*
X384300Y-73333D01*
X384500Y-74400D01*
X384300Y-75467D01*
X383800Y-76267D01*
X382900Y-76667D01*
X380500D01*
G01X388300Y-80000D02*
Y-72000D01*
X390300D01*
X391100Y-72400D01*
X391700Y-72933D01*
X392200Y-73733D01*
X392600Y-74667D01*
X392700Y-76000D01*
X392600Y-77333D01*
X392200Y-78267D01*
X391700Y-79067D01*
X391100Y-79600D01*
X390300Y-80000D01*
X388300D01*
G01X399300Y-75733D02*
X399700Y-75333D01*
X400000Y-74667D01*
X400200Y-73733D01*
X400000Y-72933D01*
X399600Y-72400D01*
X398900Y-72000D01*
X396200D01*
Y-80000D01*
X399500D01*
X400200Y-79467D01*
X400600Y-78667D01*
X400800Y-77733D01*
X400600Y-76800D01*
X400000Y-76000D01*
X399300Y-75733D01*
X396200D01*
G01X403500Y-82667D02*
X409500D01*
G01X412300Y-80000D02*
Y-72000D01*
X414300D01*
X415100Y-72400D01*
X415700Y-72933D01*
X416200Y-73733D01*
X416600Y-74667D01*
X416700Y-76000D01*
X416600Y-77333D01*
X416200Y-78267D01*
X415700Y-79067D01*
X415100Y-79600D01*
X414300Y-80000D01*
X412300D01*
G01X419500Y-82667D02*
X425500D01*
G01X431300Y-75733D02*
X431700Y-75333D01*
X432000Y-74667D01*
X432200Y-73733D01*
X432000Y-72933D01*
X431600Y-72400D01*
X430900Y-72000D01*
X428200D01*
Y-80000D01*
X431500D01*
X432200Y-79467D01*
X432600Y-78667D01*
X432800Y-77733D01*
X432600Y-76800D01*
X432000Y-76000D01*
X431300Y-75733D01*
X428200D01*
G01X436300Y-80000D02*
Y-72000D01*
X438300D01*
X439100Y-72400D01*
X439700Y-72933D01*
X440200Y-73733D01*
X440600Y-74667D01*
X440700Y-76000D01*
X440600Y-77333D01*
X440200Y-78267D01*
X439700Y-79067D01*
X439100Y-79600D01*
X438300Y-80000D01*
X436300D01*
G01X443300Y-130000D02*
Y-122000D01*
X445300D01*
X446100Y-122400D01*
X446700Y-122933D01*
X447200Y-123733D01*
X447600Y-124667D01*
X447700Y-126000D01*
X447600Y-127333D01*
X447200Y-128267D01*
X446700Y-129067D01*
X446100Y-129600D01*
X445300Y-130000D01*
X443300D01*
G01X473000D02*
Y-122000D01*
X471800Y-123600D01*
G01Y-130000D02*
X474200D01*
G01X478800Y-128800D02*
X479400Y-129467D01*
X480100Y-129867D01*
X481000Y-130000D01*
X481900Y-129733D01*
X482600Y-129200D01*
X483100Y-128267D01*
X483200Y-127200D01*
X483000Y-126133D01*
X482500Y-125467D01*
X481800Y-124933D01*
X481100Y-124800D01*
X480400Y-124933D01*
X479500Y-125467D01*
X479800Y-122000D01*
X482500D01*
M02*
